FILE_TYPE = MACRO_DRAWING;
SET COLOR_WIRE YELLOW;
SET COLOR_PROP MONO;
SET COLOR_DOT WHITE;
SET COLOR_ARC YELLOW;
SET COLOR_BODY GREEN;
SET COLOR_NOTE MONO;
SET PROP_DISPLAY VALUE;
SET PAGE_NUMBER P146;
FORCEADD OFFPAGE..2
(-1650 2050);
FORCEPROP 2 LAST $XR0 154 
J 0
(-1461 2050);
DISPLAY 0.638298 (-1461 2050);
PAINT MONO (-1461 2050);
FORCEPROP 1 LAST COMMENT_BODY TRUE
J 0
(-1695 1955);
DISPLAY 0.872340 (-1695 1955);
PAINT GREEN (-1695 1955);
DISPLAY INVISIBLE (-1695 1955);
FORCEPROP 1 LAST OFFPAGE TRUE
J 0
(-1325 1925);
DISPLAY 0.872340 (-1325 1925);
PAINT GREEN (-1325 1925);
DISPLAY INVISIBLE (-1325 1925);
FORCEPROP 2 LAST PATH I100
J 0
(-1475 2125);
DISPLAY 1.021277 (-1475 2125);
PAINT ORANGE (-1475 2125);
DISPLAY INVISIBLE (-1475 2125);
FORCEPROP 2 LAST CDS_LIB mstr_standard
J 0
(-1650 2050);
PAINT MONO (-1650 2050);
DISPLAY INVISIBLE (-1650 2050);
FORCEADD OFFPAGE..1
(-6400 3600);
FORCEPROP 2 LAST $XR1 152 
J 0
(-6802 3600);
DISPLAY 0.638298 (-6802 3600);
PAINT MONO (-6802 3600);
FORCEPROP 2 LAST $XR0 151 
J 0
(-6682 3600);
DISPLAY 0.638298 (-6682 3600);
PAINT MONO (-6682 3600);
FORCEPROP 1 LAST COMMENT_BODY TRUE
J 0
(-6275 3500);
DISPLAY 0.872340 (-6275 3500);
PAINT GREEN (-6275 3500);
DISPLAY INVISIBLE (-6275 3500);
FORCEPROP 1 LAST OFFPAGE TRUE
J 0
(-6075 3475);
DISPLAY 0.872340 (-6075 3475);
PAINT GREEN (-6075 3475);
DISPLAY INVISIBLE (-6075 3475);
FORCEPROP 2 LAST CDS_LIB mstr_standard
J 0
(-6400 3600);
PAINT MONO (-6400 3600);
DISPLAY INVISIBLE (-6400 3600);
FORCEPROP 2 LAST PATH I102
J 0
(-6350 3675);
DISPLAY 1.021277 (-6350 3675);
PAINT ORANGE (-6350 3675);
DISPLAY INVISIBLE (-6350 3675);
FORCEPROP 2 LAST BOM_COST SM_CONTROLLER
J 0
(-5950 3650);
PAINT MONO (-5950 3650);
DISPLAY INVISIBLE (-5950 3650);
FORCEPROP 2 LAST ROOM BMC
J 0
(-6650 3675);
DISPLAY 1.361702 (-6650 3675);
PAINT ORANGE (-6650 3675);
DISPLAY INVISIBLE (-6650 3675);
FORCEADD OFFPAGE..1
(-6200 4350);
FORCEPROP 1 LAST COMMENT_BODY TRUE
J 0
(-6075 4250);
DISPLAY 0.872340 (-6075 4250);
PAINT GREEN (-6075 4250);
DISPLAY INVISIBLE (-6075 4250);
FORCEPROP 1 LAST OFFPAGE TRUE
J 0
(-5875 4225);
DISPLAY 0.872340 (-5875 4225);
PAINT GREEN (-5875 4225);
DISPLAY INVISIBLE (-5875 4225);
FORCEPROP 2 LAST CDS_LIB mstr_standard
J 0
(-6200 4350);
PAINT MONO (-6200 4350);
DISPLAY INVISIBLE (-6200 4350);
FORCEPROP 2 LAST PATH I103
J 0
(-6150 4425);
DISPLAY 1.021277 (-6150 4425);
PAINT ORANGE (-6150 4425);
DISPLAY INVISIBLE (-6150 4425);
FORCEPROP 2 LAST ROOM BMC
J 0
(-6450 4425);
DISPLAY 1.361702 (-6450 4425);
PAINT ORANGE (-6450 4425);
DISPLAY INVISIBLE (-6450 4425);
FORCEPROP 2 LAST BOM_COST SM_CONTROLLER
J 0
(-5750 4400);
PAINT MONO (-5750 4400);
DISPLAY INVISIBLE (-5750 4400);
FORCEPROP 2 LAST $XR2 170 
J 0
(-6626 4350);
DISPLAY 0.638298 (-6626 4350);
PAINT MONO (-6626 4350);
DISPLAY INVISIBLE (-6626 4350);
FORCEPROP 2 LAST $XR1 118 
J 0
(-6626 4350);
DISPLAY 0.638298 (-6626 4350);
PAINT MONO (-6626 4350);
DISPLAY INVISIBLE (-6626 4350);
FORCEPROP 2 LAST $XR0 199 
J 0
(-6626 4350);
DISPLAY 0.638298 (-6626 4350);
PAINT MONO (-6626 4350);
DISPLAY INVISIBLE (-6626 4350);
FORCEADD AST2520A1-GP-GP..4
(-3875 4000);
FORCEPROP 1 LAST LOCATION U25W4
J 0
(-5225 4825);
DISPLAY 0.617021 (-5225 4825);
PAINT GREEN (-5225 4825);
FORCEPROP 1 LAST VALUE AST2520A1-GP-GP
J 0
(-5225 3150);
DISPLAY 0.617021 (-5225 3150);
PAINT GREEN (-5225 3150);
FORCEPROP 1 LAST PART_NUMBER 071.2520A.M001
J 0
(-3875 4000);
DISPLAY 0.617021 (-3875 4000);
PAINT GREEN (-3875 4000);
DISPLAY INVISIBLE (-3875 4000);
FORCEPROP 1 LAST PACK_TYPE ASIC2-GB1
J 0
(-3875 4000);
DISPLAY 0.617021 (-3875 4000);
PAINT GREEN (-3875 4000);
DISPLAY INVISIBLE (-3875 4000);
FORCEPROP 1 LAST PATH I104
J 0
(-3875 4000);
DISPLAY 0.617021 (-3875 4000);
PAINT GREEN (-3875 4000);
DISPLAY INVISIBLE (-3875 4000);
FORCEPROP 2 LAST CDS_LIB w_hdl
J 0
(-3875 4000);
PAINT MONO (-3875 4000);
DISPLAY INVISIBLE (-3875 4000);
FORCEPROP 1 LAST CDS_LMAN_SYM_OUTLINE -1350,800,1350,-800
J 0
(-3875 4000);
DISPLAY 0.468085 (-3875 4000);
PAINT GREEN (-3875 4000);
DISPLAY INVISIBLE (-3875 4000);
FORCEADD AST2520A1-GP-GP..5
(-4100 1850);
FORCEPROP 1 LAST VALUE AST2520A1-GP-GP
J 0
(-5425 850);
DISPLAY 0.617021 (-5425 850);
PAINT GREEN (-5425 850);
FORCEPROP 1 LAST LOCATION U25W4
J 0
(-5425 2825);
DISPLAY 0.617021 (-5425 2825);
PAINT GREEN (-5425 2825);
FORCEPROP 1 LAST CDS_LMAN_SYM_OUTLINE -1325,950,1325,-950
J 0
(-4100 1850);
DISPLAY 0.468085 (-4100 1850);
PAINT GREEN (-4100 1850);
DISPLAY INVISIBLE (-4100 1850);
FORCEPROP 1 LAST PACK_TYPE ASIC2-GB1
J 0
(-4100 1850);
DISPLAY 0.617021 (-4100 1850);
PAINT GREEN (-4100 1850);
DISPLAY INVISIBLE (-4100 1850);
FORCEPROP 1 LAST PATH I105
J 0
(-4100 1850);
DISPLAY 0.617021 (-4100 1850);
PAINT GREEN (-4100 1850);
DISPLAY INVISIBLE (-4100 1850);
FORCEPROP 1 LAST PART_NUMBER 071.2520A.M001
J 0
(-4100 1850);
DISPLAY 0.617021 (-4100 1850);
PAINT GREEN (-4100 1850);
DISPLAY INVISIBLE (-4100 1850);
FORCEPROP 2 LAST CDS_LIB w_hdl
J 0
(-4100 1850);
PAINT MONO (-4100 1850);
DISPLAY INVISIBLE (-4100 1850);
FORCEADD OFFPAGE..1
(-6200 4550);
FORCEPROP 1 LAST COMMENT_BODY TRUE
J 0
(-6075 4450);
DISPLAY 0.872340 (-6075 4450);
PAINT GREEN (-6075 4450);
DISPLAY INVISIBLE (-6075 4450);
FORCEPROP 1 LAST OFFPAGE TRUE
J 0
(-5875 4425);
DISPLAY 0.872340 (-5875 4425);
PAINT GREEN (-5875 4425);
DISPLAY INVISIBLE (-5875 4425);
FORCEPROP 2 LAST ROOM BMC
J 0
(-6450 4625);
DISPLAY 1.361702 (-6450 4625);
PAINT ORANGE (-6450 4625);
DISPLAY INVISIBLE (-6450 4625);
FORCEPROP 2 LAST BOM_COST SM_CONTROLLER
J 0
(-5750 4600);
PAINT MONO (-5750 4600);
DISPLAY INVISIBLE (-5750 4600);
FORCEPROP 2 LAST PATH I106
J 0
(-6150 4625);
DISPLAY 1.021277 (-6150 4625);
PAINT ORANGE (-6150 4625);
DISPLAY INVISIBLE (-6150 4625);
FORCEPROP 2 LAST CDS_LIB mstr_standard
J 0
(-6200 4550);
DISPLAY INVISIBLE (-6200 4550);
FORCEPROP 2 LAST $XR3 143 
J 0
(-6812 4550);
DISPLAY 0.638298 (-6812 4550);
PAINT MONO (-6812 4550);
FORCEPROP 2 LAST $XR2 119 
J 0
(-6692 4550);
DISPLAY 0.638298 (-6692 4550);
PAINT MONO (-6692 4550);
FORCEPROP 2 LAST $XR1 133 
J 0
(-6572 4550);
DISPLAY 0.638298 (-6572 4550);
PAINT MONO (-6572 4550);
FORCEPROP 2 LAST $XR0 120 
J 0
(-6452 4550);
DISPLAY 0.638298 (-6452 4550);
PAINT MONO (-6452 4550);
FORCEADD OFFPAGE..5
(-6350 4100);
FORCEPROP 2 LAST $XR2 119 
J 0
(-7085 4100);
DISPLAY 0.638298 (-7085 4100);
PAINT MONO (-7085 4100);
FORCEPROP 2 LAST $XR1 191 
J 0
(-6965 4100);
DISPLAY 0.638298 (-6965 4100);
PAINT MONO (-6965 4100);
FORCEPROP 2 LAST $XR0 151 
J 0
(-6845 4100);
DISPLAY 0.638298 (-6845 4100);
PAINT MONO (-6845 4100);
FORCEPROP 2 LAST CDS_LIB mstr_standard
J 0
(-6350 4100);
PAINT MONO (-6350 4100);
DISPLAY INVISIBLE (-6350 4100);
FORCEPROP 2 LAST PATH I17
J 0
(-6300 4175);
DISPLAY 1.021277 (-6300 4175);
PAINT ORANGE (-6300 4175);
DISPLAY INVISIBLE (-6300 4175);
FORCEPROP 1 LAST OFFPAGE TRUE
J 0
(-6025 3975);
DISPLAY 0.872340 (-6025 3975);
PAINT GREEN (-6025 3975);
DISPLAY INVISIBLE (-6025 3975);
FORCEPROP 1 LAST COMMENT_BODY TRUE
J 0
(-6250 4025);
DISPLAY 0.872340 (-6250 4025);
PAINT GREEN (-6250 4025);
DISPLAY INVISIBLE (-6250 4025);
FORCEADD OFFPAGE..5
(-6225 4050);
FORCEPROP 2 LAST $XR1 247 
J 0
(-7050 4050);
DISPLAY 0.638298 (-7050 4050);
PAINT MONO (-7050 4050);
FORCEPROP 2 LAST $XR0 151 
J 0
(-6930 4050);
DISPLAY 0.638298 (-6930 4050);
PAINT MONO (-6930 4050);
FORCEPROP 1 LAST COMMENT_BODY TRUE
J 0
(-6125 3975);
DISPLAY 0.872340 (-6125 3975);
PAINT GREEN (-6125 3975);
DISPLAY INVISIBLE (-6125 3975);
FORCEPROP 1 LAST OFFPAGE TRUE
J 0
(-5900 3925);
DISPLAY 0.872340 (-5900 3925);
PAINT GREEN (-5900 3925);
DISPLAY INVISIBLE (-5900 3925);
FORCEPROP 2 LAST CDS_LIB mstr_standard
J 0
(-6225 4050);
PAINT MONO (-6225 4050);
DISPLAY INVISIBLE (-6225 4050);
FORCEPROP 2 LAST PATH I18
J 0
(-6175 4125);
DISPLAY 1.021277 (-6175 4125);
PAINT ORANGE (-6175 4125);
DISPLAY INVISIBLE (-6175 4125);
FORCEADD OFFPAGE..5
(-6575 4150);
FORCEPROP 2 LAST $XR1 152 
J 0
(-6980 4150);
DISPLAY 0.638298 (-6980 4150);
PAINT MONO (-6980 4150);
FORCEPROP 2 LAST $XR0 151 
J 0
(-6860 4150);
DISPLAY 0.638298 (-6860 4150);
PAINT MONO (-6860 4150);
FORCEPROP 1 LAST COMMENT_BODY TRUE
J 0
(-6475 4075);
DISPLAY 0.872340 (-6475 4075);
PAINT GREEN (-6475 4075);
DISPLAY INVISIBLE (-6475 4075);
FORCEPROP 1 LAST OFFPAGE TRUE
J 0
(-6250 4025);
DISPLAY 0.872340 (-6250 4025);
PAINT GREEN (-6250 4025);
DISPLAY INVISIBLE (-6250 4025);
FORCEPROP 2 LAST CDS_LIB mstr_standard
J 0
(-6575 4150);
PAINT MONO (-6575 4150);
DISPLAY INVISIBLE (-6575 4150);
FORCEPROP 2 LAST PATH I19
J 0
(-6525 4225);
DISPLAY 1.021277 (-6525 4225);
PAINT ORANGE (-6525 4225);
DISPLAY INVISIBLE (-6525 4225);
FORCEADD OFFPAGE..5
(-6225 4000);
FORCEPROP 1 LAST COMMENT_BODY TRUE
J 0
(-6125 3925);
DISPLAY 0.872340 (-6125 3925);
PAINT GREEN (-6125 3925);
DISPLAY INVISIBLE (-6125 3925);
FORCEPROP 1 LAST OFFPAGE TRUE
J 0
(-5900 3875);
DISPLAY 0.872340 (-5900 3875);
PAINT GREEN (-5900 3875);
DISPLAY INVISIBLE (-5900 3875);
FORCEPROP 2 LAST CDS_LIB mstr_standard
J 0
(-6225 4000);
PAINT MONO (-6225 4000);
DISPLAY INVISIBLE (-6225 4000);
FORCEPROP 2 LAST PATH I21
J 0
(-6175 4075);
DISPLAY 1.021277 (-6175 4075);
PAINT ORANGE (-6175 4075);
DISPLAY INVISIBLE (-6175 4075);
FORCEPROP 2 LAST $XR2 119 
J 0
(-6654 4000);
DISPLAY 0.638298 (-6654 4000);
PAINT MONO (-6654 4000);
DISPLAY INVISIBLE (-6654 4000);
FORCEPROP 2 LAST $XR1 133 
J 0
(-6654 4000);
DISPLAY 0.638298 (-6654 4000);
PAINT MONO (-6654 4000);
DISPLAY INVISIBLE (-6654 4000);
FORCEPROP 2 LAST $XR0 120 
J 0
(-6654 4000);
DISPLAY 0.638298 (-6654 4000);
PAINT MONO (-6654 4000);
DISPLAY INVISIBLE (-6654 4000);
FORCEADD OFFPAGE..5
(-6225 3850);
FORCEPROP 2 LAST $XR0 154 
J 0
(-6480 3850);
DISPLAY 0.638298 (-6480 3850);
PAINT MONO (-6480 3850);
FORCEPROP 1 LAST COMMENT_BODY TRUE
J 0
(-6125 3775);
DISPLAY 0.872340 (-6125 3775);
PAINT GREEN (-6125 3775);
DISPLAY INVISIBLE (-6125 3775);
FORCEPROP 1 LAST OFFPAGE TRUE
J 0
(-5900 3725);
DISPLAY 0.872340 (-5900 3725);
PAINT GREEN (-5900 3725);
DISPLAY INVISIBLE (-5900 3725);
FORCEPROP 2 LAST CDS_LIB mstr_standard
J 0
(-6225 3850);
PAINT MONO (-6225 3850);
DISPLAY INVISIBLE (-6225 3850);
FORCEPROP 2 LAST PATH I23
J 0
(-6175 3925);
DISPLAY 1.021277 (-6175 3925);
PAINT ORANGE (-6175 3925);
DISPLAY INVISIBLE (-6175 3925);
FORCEADD OFFPAGE..1
(-7525 3900);
FORCEPROP 2 LAST $XR1 120 
J 0
(-7897 3900);
DISPLAY 0.638298 (-7897 3900);
PAINT MONO (-7897 3900);
FORCEPROP 2 LAST $XR0 157 
J 0
(-7777 3900);
DISPLAY 0.638298 (-7777 3900);
PAINT MONO (-7777 3900);
FORCEPROP 1 LAST COMMENT_BODY TRUE
J 0
(-7400 3800);
DISPLAY 0.872340 (-7400 3800);
PAINT GREEN (-7400 3800);
DISPLAY INVISIBLE (-7400 3800);
FORCEPROP 1 LAST OFFPAGE TRUE
J 0
(-7200 3775);
DISPLAY 0.872340 (-7200 3775);
PAINT GREEN (-7200 3775);
DISPLAY INVISIBLE (-7200 3775);
FORCEPROP 2 LAST CDS_LIB mstr_standard
J 0
(-7525 3900);
PAINT MONO (-7525 3900);
DISPLAY INVISIBLE (-7525 3900);
FORCEPROP 2 LAST PATH I24
J 0
(-7475 3975);
DISPLAY 1.021277 (-7475 3975);
PAINT ORANGE (-7475 3975);
DISPLAY INVISIBLE (-7475 3975);
FORCEPROP 2 LAST ROOM BMC
J 0
(-7775 3975);
DISPLAY 1.361702 (-7775 3975);
PAINT ORANGE (-7775 3975);
DISPLAY INVISIBLE (-7775 3975);
FORCEPROP 2 LAST BOM_COST SM_CONTROLLER
J 0
(-7075 3950);
PAINT MONO (-7075 3950);
DISPLAY INVISIBLE (-7075 3950);
FORCEADD OFFPAGE..1
(-7525 3825);
FORCEPROP 2 LAST $XR1 126 
J 0
(-7897 3825);
DISPLAY 0.638298 (-7897 3825);
PAINT MONO (-7897 3825);
FORCEPROP 2 LAST $XR0 119 
J 0
(-7777 3825);
DISPLAY 0.638298 (-7777 3825);
PAINT MONO (-7777 3825);
FORCEPROP 1 LAST COMMENT_BODY TRUE
J 0
(-7400 3725);
DISPLAY 0.872340 (-7400 3725);
PAINT GREEN (-7400 3725);
DISPLAY INVISIBLE (-7400 3725);
FORCEPROP 1 LAST OFFPAGE TRUE
J 0
(-7200 3700);
DISPLAY 0.872340 (-7200 3700);
PAINT GREEN (-7200 3700);
DISPLAY INVISIBLE (-7200 3700);
FORCEPROP 2 LAST CDS_LIB mstr_standard
J 0
(-7525 3825);
PAINT MONO (-7525 3825);
DISPLAY INVISIBLE (-7525 3825);
FORCEPROP 2 LAST PATH I25
J 0
(-7475 3900);
DISPLAY 1.021277 (-7475 3900);
PAINT ORANGE (-7475 3900);
DISPLAY INVISIBLE (-7475 3900);
FORCEPROP 2 LAST ROOM BMC
J 0
(-7775 3900);
DISPLAY 1.361702 (-7775 3900);
PAINT ORANGE (-7775 3900);
DISPLAY INVISIBLE (-7775 3900);
FORCEPROP 2 LAST BOM_COST SM_CONTROLLER
J 0
(-7075 3875);
PAINT MONO (-7075 3875);
DISPLAY INVISIBLE (-7075 3875);
FORCEADD RES..1
(-6950 3900);
FORCEPROP 1 LAST LOCATION R25W83
J 0
(-7150 3950);
DISPLAY 0.617021 (-7150 3950);
PAINT AQUA (-7150 3950);
FORCEPROP 1 LAST VALUE 0.0
J 2
(-6925 3925);
DISPLAY 0.617021 (-6925 3925);
PAINT SKYBLUE (-6925 3925);
FORCEPROP 1 LAST TOLERANCE 5%
J 0
(-6900 3925);
DISPLAY 0.617021 (-6900 3925);
PAINT SKYBLUE (-6900 3925);
FORCEPROP 1 LAST PACK_TYPE 0402
J 0
(-6825 3925);
DISPLAY 0.617021 (-6825 3925);
PAINT SKYBLUE (-6825 3925);
FORCEPROP 1 LAST PATH I26
J 0
(-7000 4050);
DISPLAY 0.978723 (-7000 4050);
PAINT WHITE (-7000 4050);
DISPLAY INVISIBLE (-7000 4050);
FORCEPROP 2 LAST CDS_LIB mstr_discrete
J 0
(-6950 3900);
PAINT MONO (-6950 3900);
DISPLAY INVISIBLE (-6950 3900);
FORCEPROP 1 LAST WATTAGE 1/16W
J 2
(-6975 3775);
DISPLAY 0.510638 (-6975 3775);
PAINT SKYBLUE (-6975 3775);
DISPLAY INVISIBLE (-6975 3775);
FORCEPROP 1 LAST PART_NUMBER G21497-005
J 0
(-6875 3950);
DISPLAY 0.510638 (-6875 3950);
PAINT BLUE (-6875 3950);
DISPLAY INVISIBLE (-6875 3950);
FORCEPROP 0 LAST ROOM USB
J 0
(-6775 4000);
DISPLAY 1.021277 (-6775 4000);
PAINT ORANGE (-6775 4000);
DISPLAY INVISIBLE (-6775 4000);
FORCEPROP 0 LAST BOM_COST MIO_USB
J 0
(-6775 4050);
DISPLAY 1.021277 (-6775 4050);
PAINT ORANGE (-6775 4050);
DISPLAY INVISIBLE (-6775 4050);
FORCEPROP 1 LAST MATERIAL CHIP
J 0
(-7175 3925);
DISPLAY 0.617021 (-7175 3925);
PAINT SKYBLUE (-7175 3925);
DISPLAY INVISIBLE (-7175 3925);
FORCEPROP 1 LASTPIN (-7050 3900) $PN 1
J 0
(-7038 3912);
DISPLAY 0.787234 (-7038 3912);
PAINT ORANGE (-7038 3912);
DISPLAY INVISIBLE (-7038 3912);
FORCEPROP 1 LASTPIN (-6850 3900) $PN 2
J 0
(-6888 3912);
DISPLAY 0.787234 (-6888 3912);
PAINT ORANGE (-6888 3912);
DISPLAY INVISIBLE (-6888 3912);
FORCEADD RES..1
(-6950 3825);
FORCEPROP 1 LAST TOLERANCE 5%
J 0
(-6900 3775);
DISPLAY 0.617021 (-6900 3775);
PAINT SKYBLUE (-6900 3775);
FORCEPROP 1 LAST VALUE 0.0
J 2
(-7000 3750);
DISPLAY 0.617021 (-7000 3750);
PAINT SKYBLUE (-7000 3750);
FORCEPROP 1 LAST LOCATION R25W84
J 0
(-7150 3775);
DISPLAY 0.617021 (-7150 3775);
PAINT AQUA (-7150 3775);
FORCEPROP 1 LAST PACK_TYPE 0402
J 0
(-6825 3775);
DISPLAY 0.617021 (-6825 3775);
PAINT SKYBLUE (-6825 3775);
FORCEPROP 0 LAST BOM_COST MIO_USB
J 0
(-6775 3975);
DISPLAY 1.021277 (-6775 3975);
PAINT ORANGE (-6775 3975);
DISPLAY INVISIBLE (-6775 3975);
FORCEPROP 0 LAST ROOM USB
J 0
(-6775 3925);
DISPLAY 1.021277 (-6775 3925);
PAINT ORANGE (-6775 3925);
DISPLAY INVISIBLE (-6775 3925);
FORCEPROP 1 LAST PART_NUMBER G21497-005
J 0
(-6875 3875);
DISPLAY 0.510638 (-6875 3875);
PAINT BLUE (-6875 3875);
DISPLAY INVISIBLE (-6875 3875);
FORCEPROP 1 LAST WATTAGE 1/16W
J 2
(-6975 3700);
DISPLAY 0.510638 (-6975 3700);
PAINT SKYBLUE (-6975 3700);
DISPLAY INVISIBLE (-6975 3700);
FORCEPROP 2 LAST CDS_LIB mstr_discrete
J 0
(-6950 3825);
PAINT MONO (-6950 3825);
DISPLAY INVISIBLE (-6950 3825);
FORCEPROP 1 LAST MATERIAL CHIP
J 0
(-7175 3850);
DISPLAY 0.617021 (-7175 3850);
PAINT SKYBLUE (-7175 3850);
DISPLAY INVISIBLE (-7175 3850);
FORCEPROP 1 LAST PATH I27
J 0
(-7000 3975);
DISPLAY 0.978723 (-7000 3975);
PAINT WHITE (-7000 3975);
DISPLAY INVISIBLE (-7000 3975);
FORCEPROP 1 LASTPIN (-7050 3825) $PN 1
J 0
(-7038 3837);
DISPLAY 0.787234 (-7038 3837);
PAINT ORANGE (-7038 3837);
DISPLAY INVISIBLE (-7038 3837);
FORCEPROP 1 LASTPIN (-6850 3825) $PN 2
J 0
(-6888 3837);
DISPLAY 0.787234 (-6888 3837);
PAINT ORANGE (-6888 3837);
DISPLAY INVISIBLE (-6888 3837);
FORCEADD OFFPAGE..1
(-6375 3400);
FORCEPROP 2 LAST $XR0 119 
J 0
(-6657 3400);
DISPLAY 0.638298 (-6657 3400);
PAINT MONO (-6657 3400);
FORCEPROP 2 LAST $XR2 170 
J 0
(-6897 3400);
DISPLAY 0.638298 (-6897 3400);
PAINT MONO (-6897 3400);
FORCEPROP 2 LAST $XR3 95 
J 0
(-6987 3400);
DISPLAY 0.638298 (-6987 3400);
PAINT MONO (-6987 3400);
FORCEPROP 2 LAST $XR4 120 
J 0
(-7107 3400);
DISPLAY 0.638298 (-7107 3400);
PAINT MONO (-7107 3400);
FORCEPROP 2 LAST $XR1 133 
J 0
(-6777 3400);
DISPLAY 0.638298 (-6777 3400);
PAINT MONO (-6777 3400);
FORCEPROP 2 LAST CDS_LIB mstr_standard
J 0
(-6375 3400);
PAINT MONO (-6375 3400);
DISPLAY INVISIBLE (-6375 3400);
FORCEPROP 2 LAST BOM_COST SM_CONTROLLER
J 0
(-5925 3450);
PAINT MONO (-5925 3450);
DISPLAY INVISIBLE (-5925 3450);
FORCEPROP 2 LAST ROOM BMC
J 0
(-6625 3475);
DISPLAY 1.361702 (-6625 3475);
PAINT ORANGE (-6625 3475);
DISPLAY INVISIBLE (-6625 3475);
FORCEPROP 2 LAST PATH I28
J 0
(-6650 3450);
DISPLAY 1.021277 (-6650 3450);
PAINT ORANGE (-6650 3450);
DISPLAY INVISIBLE (-6650 3450);
FORCEPROP 1 LAST OFFPAGE TRUE
J 0
(-6050 3275);
DISPLAY 0.872340 (-6050 3275);
PAINT GREEN (-6050 3275);
DISPLAY INVISIBLE (-6050 3275);
FORCEPROP 1 LAST COMMENT_BODY TRUE
J 0
(-6250 3300);
DISPLAY 0.872340 (-6250 3300);
PAINT GREEN (-6250 3300);
DISPLAY INVISIBLE (-6250 3300);
FORCEADD OFFPAGE..5
(-6425 3450);
FORCEPROP 2 LAST $XR0 120 
J 0
(-6680 3450);
DISPLAY 0.638298 (-6680 3450);
PAINT MONO (-6680 3450);
FORCEPROP 2 LAST $XR3 182 
J 0
(-7040 3450);
DISPLAY 0.638298 (-7040 3450);
PAINT MONO (-7040 3450);
FORCEPROP 2 LAST $XR2 119 
J 0
(-6920 3450);
DISPLAY 0.638298 (-6920 3450);
PAINT MONO (-6920 3450);
FORCEPROP 2 LAST $XR1 133 
J 0
(-6800 3450);
DISPLAY 0.638298 (-6800 3450);
PAINT MONO (-6800 3450);
FORCEPROP 2 LAST PATH I29
J 0
(-6675 3500);
DISPLAY 1.021277 (-6675 3500);
PAINT ORANGE (-6675 3500);
DISPLAY INVISIBLE (-6675 3500);
FORCEPROP 2 LAST ROOM BMC
J 0
(-6675 3525);
DISPLAY 1.361702 (-6675 3525);
PAINT ORANGE (-6675 3525);
DISPLAY INVISIBLE (-6675 3525);
FORCEPROP 2 LAST BOM_COST SM_CONTROLLER
J 0
(-5975 3500);
PAINT MONO (-5975 3500);
DISPLAY INVISIBLE (-5975 3500);
FORCEPROP 2 LAST CDS_LIB mstr_standard
J 2
(-6425 3450);
PAINT ORANGE (-6425 3450);
DISPLAY INVISIBLE (-6425 3450);
FORCEPROP 1 LAST OFFPAGE TRUE
J 0
(-6100 3325);
DISPLAY 0.872340 (-6100 3325);
PAINT GREEN (-6100 3325);
DISPLAY INVISIBLE (-6100 3325);
FORCEPROP 1 LAST COMMENT_BODY TRUE
J 0
(-6325 3375);
DISPLAY 0.872340 (-6325 3375);
PAINT GREEN (-6325 3375);
DISPLAY INVISIBLE (-6325 3375);
FORCEADD OFFPAGE..5
(-6400 3650);
FORCEPROP 2 LAST $XR0 175 
J 0
(-6655 3650);
DISPLAY 0.638298 (-6655 3650);
PAINT MONO (-6655 3650);
FORCEPROP 2 LAST ROOM BMC
J 0
(-6650 3725);
DISPLAY 1.361702 (-6650 3725);
PAINT ORANGE (-6650 3725);
DISPLAY INVISIBLE (-6650 3725);
FORCEPROP 2 LAST BOM_COST SM_CONTROLLER
J 0
(-5950 3700);
PAINT MONO (-5950 3700);
DISPLAY INVISIBLE (-5950 3700);
FORCEPROP 2 LAST CDS_LIB mstr_standard
J 0
(-6400 3650);
PAINT MONO (-6400 3650);
DISPLAY INVISIBLE (-6400 3650);
FORCEPROP 2 LAST PATH I30
J 0
(-6650 3700);
DISPLAY 1.021277 (-6650 3700);
PAINT ORANGE (-6650 3700);
DISPLAY INVISIBLE (-6650 3700);
FORCEPROP 1 LAST OFFPAGE TRUE
J 0
(-6075 3525);
DISPLAY 0.872340 (-6075 3525);
PAINT GREEN (-6075 3525);
DISPLAY INVISIBLE (-6075 3525);
FORCEPROP 1 LAST COMMENT_BODY TRUE
J 0
(-6300 3575);
DISPLAY 0.872340 (-6300 3575);
PAINT GREEN (-6300 3575);
DISPLAY INVISIBLE (-6300 3575);
FORCEADD OFFPAGE..5
(-6400 3700);
FORCEPROP 2 LAST $XR2 151 
J 0
(-6895 3700);
DISPLAY 0.638298 (-6895 3700);
PAINT MONO (-6895 3700);
FORCEPROP 2 LAST $XR0 120 
J 0
(-6655 3700);
DISPLAY 0.638298 (-6655 3700);
PAINT MONO (-6655 3700);
FORCEPROP 2 LAST $XR1 133 
J 0
(-6775 3700);
DISPLAY 0.638298 (-6775 3700);
PAINT MONO (-6775 3700);
FORCEPROP 2 LAST $XR3 175 
J 0
(-6895 3700);
DISPLAY 0.638298 (-6895 3700);
PAINT MONO (-6895 3700);
FORCEPROP 1 LAST COMMENT_BODY TRUE
J 0
(-6300 3625);
DISPLAY 0.872340 (-6300 3625);
PAINT GREEN (-6300 3625);
DISPLAY INVISIBLE (-6300 3625);
FORCEPROP 1 LAST OFFPAGE TRUE
J 0
(-6075 3575);
DISPLAY 0.872340 (-6075 3575);
PAINT GREEN (-6075 3575);
DISPLAY INVISIBLE (-6075 3575);
FORCEPROP 2 LAST CDS_LIB mstr_standard
J 0
(-6400 3700);
PAINT ORANGE (-6400 3700);
DISPLAY INVISIBLE (-6400 3700);
FORCEPROP 2 LAST ROOM BMC
J 0
(-6650 3775);
DISPLAY 1.361702 (-6650 3775);
PAINT ORANGE (-6650 3775);
DISPLAY INVISIBLE (-6650 3775);
FORCEPROP 2 LAST BOM_COST SM_CONTROLLER
J 0
(-5950 3750);
PAINT MONO (-5950 3750);
DISPLAY INVISIBLE (-5950 3750);
FORCEPROP 2 LAST PATH I31
J 0
(-6650 3750);
DISPLAY 1.021277 (-6650 3750);
PAINT ORANGE (-6650 3750);
DISPLAY INVISIBLE (-6650 3750);
FORCEADD OFFPAGE..5
(-6400 3750);
FORCEPROP 2 LAST $XR0 151 
J 0
(-6655 3750);
DISPLAY 0.638298 (-6655 3750);
PAINT MONO (-6655 3750);
FORCEPROP 2 LAST BOM_COST SM_CONTROLLER
J 0
(-5950 3800);
PAINT MONO (-5950 3800);
DISPLAY INVISIBLE (-5950 3800);
FORCEPROP 2 LAST ROOM BMC
J 0
(-6650 3825);
DISPLAY 1.361702 (-6650 3825);
PAINT ORANGE (-6650 3825);
DISPLAY INVISIBLE (-6650 3825);
FORCEPROP 2 LAST CDS_LIB mstr_standard
J 0
(-6400 3750);
PAINT MONO (-6400 3750);
DISPLAY INVISIBLE (-6400 3750);
FORCEPROP 2 LAST PATH I32
J 0
(-6650 3800);
DISPLAY 1.021277 (-6650 3800);
PAINT ORANGE (-6650 3800);
DISPLAY INVISIBLE (-6650 3800);
FORCEPROP 1 LAST OFFPAGE TRUE
J 0
(-6075 3625);
DISPLAY 0.872340 (-6075 3625);
PAINT GREEN (-6075 3625);
DISPLAY INVISIBLE (-6075 3625);
FORCEPROP 1 LAST COMMENT_BODY TRUE
J 0
(-6300 3675);
DISPLAY 0.872340 (-6300 3675);
PAINT GREEN (-6300 3675);
DISPLAY INVISIBLE (-6300 3675);
FORCEADD OFFPAGE..1
(-6400 3550);
FORCEPROP 2 LAST $XR0 139 
J 0
(-6652 3550);
DISPLAY 0.638298 (-6652 3550);
PAINT MONO (-6652 3550);
FORCEPROP 2 LAST $XR1 119 
J 0
(-6652 3550);
DISPLAY 0.638298 (-6652 3550);
PAINT MONO (-6652 3550);
FORCEPROP 1 LAST COMMENT_BODY TRUE
J 0
(-6275 3450);
DISPLAY 0.872340 (-6275 3450);
PAINT GREEN (-6275 3450);
DISPLAY INVISIBLE (-6275 3450);
FORCEPROP 1 LAST OFFPAGE TRUE
J 0
(-6075 3425);
DISPLAY 0.872340 (-6075 3425);
PAINT GREEN (-6075 3425);
DISPLAY INVISIBLE (-6075 3425);
FORCEPROP 2 LAST PATH I33
J 0
(-6650 3600);
DISPLAY 1.021277 (-6650 3600);
PAINT ORANGE (-6650 3600);
DISPLAY INVISIBLE (-6650 3600);
FORCEPROP 2 LAST BOM_COST SM_CONTROLLER
J 0
(-5950 3600);
PAINT MONO (-5950 3600);
DISPLAY INVISIBLE (-5950 3600);
FORCEPROP 2 LAST ROOM BMC
J 0
(-6650 3625);
DISPLAY 1.361702 (-6650 3625);
PAINT ORANGE (-6650 3625);
DISPLAY INVISIBLE (-6650 3625);
FORCEPROP 2 LAST CDS_LIB mstr_standard
J 0
(-6400 3550);
PAINT ORANGE (-6400 3550);
DISPLAY INVISIBLE (-6400 3550);
FORCEADD RES..2
R 1
(-1175 4150);
FORCEPROP 1 LAST WATTAGE 1/16W
J 0
(-1100 3965);
DISPLAY 0.617021 (-1100 3965);
PAINT SKYBLUE (-1100 3965);
FORCEPROP 1 LAST TOLERANCE 1%
J 0
(-1100 3995);
DISPLAY 0.617021 (-1100 3995);
PAINT SKYBLUE (-1100 3995);
FORCEPROP 1 LAST VALUE 8.2K
J 0
(-1100 4045);
DISPLAY 0.617021 (-1100 4045);
PAINT SKYBLUE (-1100 4045);
FORCEPROP 1 LAST MATERIAL CHIP
J 0
(-1100 3915);
DISPLAY 0.617021 (-1100 3915);
PAINT SKYBLUE (-1100 3915);
FORCEPROP 1 LAST LOCATION R1T25
J 0
(-1100 4095);
DISPLAY 0.617021 (-1100 4095);
PAINT AQUA (-1100 4095);
FORCEPROP 1 LAST PACK_TYPE 0402
J 0
(-1100 3840);
DISPLAY 0.617021 (-1100 3840);
PAINT SKYBLUE (-1100 3840);
FORCEPROP 1 LAST PART_NUMBER G21796-345
J 0
(-1100 3890);
DISPLAY 0.617021 (-1100 3890);
PAINT BLUE (-1100 3890);
FORCEPROP 1 LAST PATH I35
R 1
J 0
(-1350 4200);
DISPLAY 0.978723 (-1350 4200);
PAINT WHITE (-1350 4200);
DISPLAY INVISIBLE (-1350 4200);
FORCEPROP 2 LAST CDS_LIB mstr_discrete
J 0
(-1175 4150);
PAINT MONO (-1175 4150);
DISPLAY INVISIBLE (-1175 4150);
FORCEPROP 0 LAST BOM_COST SM_CONTROLLER
R 1
J 0
(-1500 4200);
DISPLAY 1.021277 (-1500 4200);
PAINT ORANGE (-1500 4200);
DISPLAY INVISIBLE (-1500 4200);
FORCEPROP 0 LAST ROOM BMC
R 1
J 0
(-1400 4200);
DISPLAY 0.617021 (-1400 4200);
PAINT ORANGE (-1400 4200);
DISPLAY INVISIBLE (-1400 4200);
FORCEPROP 1 LASTPIN (-1075 4150) $PN 2
R 1
J 0
(-1085 4155);
DISPLAY 0.787234 (-1085 4155);
PAINT ORANGE (-1085 4155);
DISPLAY INVISIBLE (-1085 4155);
FORCEPROP 1 LASTPIN (-1275 4150) $PN 1
R 1
J 0
(-1237 4155);
DISPLAY 0.787234 (-1237 4155);
PAINT ORANGE (-1237 4155);
DISPLAY INVISIBLE (-1237 4155);
FORCEADD GND..1
R 1
(-275 4200);
FORCEPROP 3 LASTPIN (-325 4200) SIG_NAME GND\g
J 0
(-315 4210);
DISPLAY 0.659574 (-315 4210);
PAINT MONO (-315 4210);
DISPLAY INVISIBLE (-315 4210);
FORCEPROP 1 LAST HDL_POWER GND
R 1
J 0
(-425 4200);
DISPLAY 0.872340 (-425 4200);
PAINT GREEN (-425 4200);
DISPLAY INVISIBLE (-425 4200);
FORCEPROP 1 LAST BODY_TYPE PLUMBING
R 1
J 0
(-232 4155);
DISPLAY 0.340426 (-232 4155);
PAINT GREEN (-232 4155);
DISPLAY INVISIBLE (-232 4155);
FORCEPROP 1 LAST VOLTAGE 0.0V
R 1
J 0
(-232 4155);
DISPLAY 0.340426 (-232 4155);
PAINT SKYBLUE (-232 4155);
DISPLAY INVISIBLE (-232 4155);
FORCEPROP 2 LAST CDS_LIB mstr_symbols
R 1
J 0
(-275 4200);
PAINT ORANGE (-275 4200);
DISPLAY INVISIBLE (-275 4200);
FORCEPROP 1 LAST SIZE 1B
R 1
J 0
(-225 4275);
DISPLAY 0.872340 (-225 4275);
PAINT AQUA (-225 4275);
DISPLAY INVISIBLE (-225 4275);
FORCEPROP 1 LAST PATH I36
R 1
J 0
(-275 4275);
DISPLAY 0.872340 (-275 4275);
PAINT AQUA (-275 4275);
DISPLAY INVISIBLE (-275 4275);
FORCEADD RES..2
R 1
(-725 4200);
FORCEPROP 1 LAST WATTAGE 1/16W
J 0
(-775 3965);
DISPLAY 0.617021 (-775 3965);
PAINT SKYBLUE (-775 3965);
FORCEPROP 1 LAST LOCATION R1T26
J 0
(-775 4120);
DISPLAY 0.617021 (-775 4120);
PAINT AQUA (-775 4120);
FORCEPROP 1 LAST VALUE 8.2K
J 0
(-775 4070);
DISPLAY 0.617021 (-775 4070);
PAINT SKYBLUE (-775 4070);
FORCEPROP 1 LAST TOLERANCE 1%
J 0
(-775 4020);
DISPLAY 0.617021 (-775 4020);
PAINT SKYBLUE (-775 4020);
FORCEPROP 1 LAST MATERIAL CHIP
J 0
(-775 3915);
DISPLAY 0.617021 (-775 3915);
PAINT SKYBLUE (-775 3915);
FORCEPROP 1 LAST PART_NUMBER G21796-345
J 0
(-775 3865);
DISPLAY 0.617021 (-775 3865);
PAINT BLUE (-775 3865);
FORCEPROP 1 LAST PACK_TYPE 0402
J 0
(-750 3815);
DISPLAY 0.617021 (-750 3815);
PAINT SKYBLUE (-750 3815);
FORCEPROP 1 LASTPIN (-625 4200) $PN 2
R 1
J 0
(-635 4205);
DISPLAY 0.787234 (-635 4205);
PAINT ORANGE (-635 4205);
DISPLAY INVISIBLE (-635 4205);
FORCEPROP 1 LASTPIN (-825 4200) $PN 1
R 1
J 0
(-787 4205);
DISPLAY 0.787234 (-787 4205);
PAINT ORANGE (-787 4205);
DISPLAY INVISIBLE (-787 4205);
FORCEPROP 2 LAST CDS_LIB mstr_discrete
R 1
J 0
(-725 4200);
PAINT ORANGE (-725 4200);
DISPLAY INVISIBLE (-725 4200);
FORCEPROP 2 LAST CDS_SEC 1
R 1
J 0
(-950 4250);
DISPLAY 1.021277 (-950 4250);
PAINT ORANGE (-950 4250);
DISPLAY INVISIBLE (-950 4250);
FORCEPROP 2 LAST $SEC 1
R 1
J 0
(-950 4250);
DISPLAY 0.680851 (-950 4250);
PAINT MONO (-950 4250);
DISPLAY INVISIBLE (-950 4250);
FORCEPROP 0 LAST ROOM BMC
R 1
J 0
(-950 4250);
DISPLAY 0.617021 (-950 4250);
PAINT ORANGE (-950 4250);
DISPLAY INVISIBLE (-950 4250);
FORCEPROP 0 LAST BOM_COST SM_CONTROLLER
R 1
J 0
(-1050 4250);
DISPLAY 1.021277 (-1050 4250);
PAINT ORANGE (-1050 4250);
DISPLAY INVISIBLE (-1050 4250);
FORCEPROP 1 LAST PATH I37
R 1
J 0
(-900 4250);
DISPLAY 0.978723 (-900 4250);
PAINT WHITE (-900 4250);
DISPLAY INVISIBLE (-900 4250);
FORCEPROP 2 LAST CDS_LOCATION R1T26
R 1
J 0
(-850 4245);
DISPLAY 0.617021 (-850 4245);
PAINT AQUA (-850 4245);
DISPLAY INVISIBLE (-850 4245);
FORCEADD OFFPAGE..3
(-1625 4350);
FORCEPROP 2 LAST $XR0 115 
J 0
(-1411 4350);
DISPLAY 0.638298 (-1411 4350);
PAINT MONO (-1411 4350);
FORCEPROP 1 LAST COMMENT_BODY TRUE
J 0
(-1675 4250);
DISPLAY 0.872340 (-1675 4250);
PAINT GREEN (-1675 4250);
DISPLAY INVISIBLE (-1675 4250);
FORCEPROP 1 LAST OFFPAGE TRUE
J 0
(-1300 4225);
DISPLAY 0.872340 (-1300 4225);
PAINT GREEN (-1300 4225);
DISPLAY INVISIBLE (-1300 4225);
FORCEPROP 2 LAST CDS_LIB mstr_standard
J 0
(-1625 4350);
PAINT ORANGE (-1625 4350);
DISPLAY INVISIBLE (-1625 4350);
FORCEPROP 2 LAST PATH I38
J 0
(-1400 4400);
DISPLAY 1.021277 (-1400 4400);
PAINT ORANGE (-1400 4400);
DISPLAY INVISIBLE (-1400 4400);
FORCEADD OFFPAGE..3
(-1625 4300);
FORCEPROP 2 LAST $XR0 115 
J 0
(-1411 4300);
DISPLAY 0.638298 (-1411 4300);
PAINT MONO (-1411 4300);
FORCEPROP 1 LAST COMMENT_BODY TRUE
J 0
(-1675 4200);
DISPLAY 0.872340 (-1675 4200);
PAINT GREEN (-1675 4200);
DISPLAY INVISIBLE (-1675 4200);
FORCEPROP 1 LAST OFFPAGE TRUE
J 0
(-1300 4175);
DISPLAY 0.872340 (-1300 4175);
PAINT GREEN (-1300 4175);
DISPLAY INVISIBLE (-1300 4175);
FORCEPROP 2 LAST PATH I39
J 0
(-1400 4350);
DISPLAY 1.021277 (-1400 4350);
PAINT ORANGE (-1400 4350);
DISPLAY INVISIBLE (-1400 4350);
FORCEPROP 2 LAST CDS_LIB mstr_standard
J 0
(-1625 4300);
PAINT ORANGE (-1625 4300);
DISPLAY INVISIBLE (-1625 4300);
FORCEADD OFFPAGE..1
(-6550 4400);
FORCEPROP 2 LAST $XR2 119 
J 0
(-7042 4400);
DISPLAY 0.638298 (-7042 4400);
PAINT MONO (-7042 4400);
FORCEPROP 2 LAST $XR1 157 
J 0
(-6922 4400);
DISPLAY 0.638298 (-6922 4400);
PAINT MONO (-6922 4400);
FORCEPROP 2 LAST $XR0 108 
J 0
(-6802 4400);
DISPLAY 0.638298 (-6802 4400);
PAINT MONO (-6802 4400);
FORCEPROP 1 LAST COMMENT_BODY TRUE
J 0
(-6425 4300);
DISPLAY 0.872340 (-6425 4300);
PAINT GREEN (-6425 4300);
DISPLAY INVISIBLE (-6425 4300);
FORCEPROP 1 LAST OFFPAGE TRUE
J 0
(-6225 4275);
DISPLAY 0.872340 (-6225 4275);
PAINT GREEN (-6225 4275);
DISPLAY INVISIBLE (-6225 4275);
FORCEPROP 2 LAST ROOM BMC
J 0
(-6800 4475);
DISPLAY 1.361702 (-6800 4475);
PAINT ORANGE (-6800 4475);
DISPLAY INVISIBLE (-6800 4475);
FORCEPROP 2 LAST BOM_COST SM_CONTROLLER
J 0
(-6100 4450);
PAINT MONO (-6100 4450);
DISPLAY INVISIBLE (-6100 4450);
FORCEPROP 2 LAST PATH I4
J 0
(-6500 4475);
DISPLAY 1.021277 (-6500 4475);
PAINT ORANGE (-6500 4475);
DISPLAY INVISIBLE (-6500 4475);
FORCEPROP 2 LAST CDS_LIB mstr_standard
J 0
(-6550 4400);
PAINT MONO (-6550 4400);
DISPLAY INVISIBLE (-6550 4400);
FORCEADD OFFPAGE..3
(-1625 4500);
FORCEPROP 2 LAST $XR0 115 
J 0
(-1411 4500);
DISPLAY 0.638298 (-1411 4500);
PAINT MONO (-1411 4500);
FORCEPROP 1 LAST COMMENT_BODY TRUE
J 0
(-1675 4400);
DISPLAY 0.872340 (-1675 4400);
PAINT GREEN (-1675 4400);
DISPLAY INVISIBLE (-1675 4400);
FORCEPROP 1 LAST OFFPAGE TRUE
J 0
(-1300 4375);
DISPLAY 0.872340 (-1300 4375);
PAINT GREEN (-1300 4375);
DISPLAY INVISIBLE (-1300 4375);
FORCEPROP 2 LAST CDS_LIB mstr_standard
J 0
(-1625 4500);
PAINT ORANGE (-1625 4500);
DISPLAY INVISIBLE (-1625 4500);
FORCEPROP 2 LAST PATH I40
J 0
(-1400 4550);
DISPLAY 1.021277 (-1400 4550);
PAINT ORANGE (-1400 4550);
DISPLAY INVISIBLE (-1400 4550);
FORCEADD OFFPAGE..3
(-1625 4450);
FORCEPROP 2 LAST $XR0 115 
J 0
(-1411 4450);
DISPLAY 0.638298 (-1411 4450);
PAINT MONO (-1411 4450);
FORCEPROP 2 LAST $XR1 ?
J 0
(-1411 4414);
DISPLAY 0.638298 (-1411 4414);
PAINT MONO (-1411 4414);
FORCEPROP 1 LAST COMMENT_BODY TRUE
J 0
(-1675 4350);
DISPLAY 0.872340 (-1675 4350);
PAINT GREEN (-1675 4350);
DISPLAY INVISIBLE (-1675 4350);
FORCEPROP 1 LAST OFFPAGE TRUE
J 0
(-1300 4325);
DISPLAY 0.872340 (-1300 4325);
PAINT GREEN (-1300 4325);
DISPLAY INVISIBLE (-1300 4325);
FORCEPROP 2 LAST PATH I41
J 0
(-1400 4500);
DISPLAY 1.021277 (-1400 4500);
PAINT ORANGE (-1400 4500);
DISPLAY INVISIBLE (-1400 4500);
FORCEPROP 2 LAST CDS_LIB mstr_standard
J 0
(-1625 4450);
PAINT ORANGE (-1625 4450);
DISPLAY INVISIBLE (-1625 4450);
FORCEADD OFFPAGE..2
(-1600 3850);
FORCEPROP 2 LAST $XR1 155 
J 0
(-1291 3850);
DISPLAY 0.638298 (-1291 3850);
PAINT MONO (-1291 3850);
FORCEPROP 2 LAST $XR0 120 
J 0
(-1411 3850);
DISPLAY 0.638298 (-1411 3850);
PAINT MONO (-1411 3850);
FORCEPROP 1 LAST COMMENT_BODY TRUE
J 0
(-1645 3755);
DISPLAY 0.872340 (-1645 3755);
PAINT GREEN (-1645 3755);
DISPLAY INVISIBLE (-1645 3755);
FORCEPROP 1 LAST OFFPAGE TRUE
J 0
(-1275 3725);
DISPLAY 0.872340 (-1275 3725);
PAINT GREEN (-1275 3725);
DISPLAY INVISIBLE (-1275 3725);
FORCEPROP 2 LAST CDS_LIB mstr_standard
J 0
(-1600 3850);
PAINT ORANGE (-1600 3850);
DISPLAY INVISIBLE (-1600 3850);
FORCEPROP 2 LAST PATH I42
J 0
(-1275 3900);
DISPLAY 1.021277 (-1275 3900);
PAINT ORANGE (-1275 3900);
DISPLAY INVISIBLE (-1275 3900);
FORCEADD OFFPAGE..2
(-1600 3900);
FORCEPROP 2 LAST $XR1 155 
J 0
(-1291 3900);
DISPLAY 0.638298 (-1291 3900);
PAINT MONO (-1291 3900);
FORCEPROP 2 LAST $XR0 120 
J 0
(-1411 3900);
DISPLAY 0.638298 (-1411 3900);
PAINT MONO (-1411 3900);
FORCEPROP 1 LAST COMMENT_BODY TRUE
J 0
(-1645 3805);
DISPLAY 0.872340 (-1645 3805);
PAINT GREEN (-1645 3805);
DISPLAY INVISIBLE (-1645 3805);
FORCEPROP 1 LAST OFFPAGE TRUE
J 0
(-1275 3775);
DISPLAY 0.872340 (-1275 3775);
PAINT GREEN (-1275 3775);
DISPLAY INVISIBLE (-1275 3775);
FORCEPROP 2 LAST CDS_LIB mstr_standard
J 0
(-1600 3900);
PAINT ORANGE (-1600 3900);
DISPLAY INVISIBLE (-1600 3900);
FORCEPROP 2 LAST PATH I43
J 0
(-1275 3950);
DISPLAY 1.021277 (-1275 3950);
PAINT ORANGE (-1275 3950);
DISPLAY INVISIBLE (-1275 3950);
FORCEADD OFFPAGE..2
(-1600 3950);
FORCEPROP 2 LAST $XR1 155 
J 0
(-1291 3950);
DISPLAY 0.638298 (-1291 3950);
PAINT MONO (-1291 3950);
FORCEPROP 2 LAST $XR0 120 
J 0
(-1411 3950);
DISPLAY 0.638298 (-1411 3950);
PAINT MONO (-1411 3950);
FORCEPROP 1 LAST COMMENT_BODY TRUE
J 0
(-1645 3855);
DISPLAY 0.872340 (-1645 3855);
PAINT GREEN (-1645 3855);
DISPLAY INVISIBLE (-1645 3855);
FORCEPROP 1 LAST OFFPAGE TRUE
J 0
(-1275 3825);
DISPLAY 0.872340 (-1275 3825);
PAINT GREEN (-1275 3825);
DISPLAY INVISIBLE (-1275 3825);
FORCEPROP 2 LAST CDS_LIB mstr_standard
J 0
(-1600 3950);
PAINT ORANGE (-1600 3950);
DISPLAY INVISIBLE (-1600 3950);
FORCEPROP 2 LAST PATH I44
J 0
(-1275 4000);
DISPLAY 1.021277 (-1275 4000);
PAINT ORANGE (-1275 4000);
DISPLAY INVISIBLE (-1275 4000);
FORCEADD OFFPAGE..2
(-1600 4000);
FORCEPROP 2 LAST $XR1 155 
J 0
(-1291 4000);
DISPLAY 0.638298 (-1291 4000);
PAINT MONO (-1291 4000);
FORCEPROP 2 LAST $XR0 120 
J 0
(-1411 4000);
DISPLAY 0.638298 (-1411 4000);
PAINT MONO (-1411 4000);
FORCEPROP 1 LAST COMMENT_BODY TRUE
J 0
(-1645 3905);
DISPLAY 0.872340 (-1645 3905);
PAINT GREEN (-1645 3905);
DISPLAY INVISIBLE (-1645 3905);
FORCEPROP 1 LAST OFFPAGE TRUE
J 0
(-1275 3875);
DISPLAY 0.872340 (-1275 3875);
PAINT GREEN (-1275 3875);
DISPLAY INVISIBLE (-1275 3875);
FORCEPROP 2 LAST CDS_LIB mstr_standard
J 0
(-1600 4000);
PAINT ORANGE (-1600 4000);
DISPLAY INVISIBLE (-1600 4000);
FORCEPROP 2 LAST PATH I45
J 0
(-1275 4050);
DISPLAY 1.021277 (-1275 4050);
PAINT ORANGE (-1275 4050);
DISPLAY INVISIBLE (-1275 4050);
FORCEADD OFFPAGE..2
(-1600 3750);
FORCEPROP 2 LAST $XR1 155 
J 0
(-1291 3750);
DISPLAY 0.638298 (-1291 3750);
PAINT MONO (-1291 3750);
FORCEPROP 2 LAST $XR0 120 
J 0
(-1411 3750);
DISPLAY 0.638298 (-1411 3750);
PAINT MONO (-1411 3750);
FORCEPROP 1 LAST COMMENT_BODY TRUE
J 0
(-1645 3655);
DISPLAY 0.872340 (-1645 3655);
PAINT GREEN (-1645 3655);
DISPLAY INVISIBLE (-1645 3655);
FORCEPROP 1 LAST OFFPAGE TRUE
J 0
(-1275 3625);
DISPLAY 0.872340 (-1275 3625);
PAINT GREEN (-1275 3625);
DISPLAY INVISIBLE (-1275 3625);
FORCEPROP 2 LAST CDS_LIB mstr_standard
J 0
(-1600 3750);
PAINT ORANGE (-1600 3750);
DISPLAY INVISIBLE (-1600 3750);
FORCEPROP 2 LAST PATH I46
J 0
(-1275 3800);
DISPLAY 1.021277 (-1275 3800);
PAINT ORANGE (-1275 3800);
DISPLAY INVISIBLE (-1275 3800);
FORCEADD OFFPAGE..2
(-1600 3700);
FORCEPROP 2 LAST $XR0 120 
J 0
(-1411 3700);
DISPLAY 0.638298 (-1411 3700);
PAINT MONO (-1411 3700);
FORCEPROP 2 LAST $XR1 155 
J 0
(-1291 3700);
DISPLAY 0.638298 (-1291 3700);
PAINT MONO (-1291 3700);
FORCEPROP 1 LAST COMMENT_BODY TRUE
J 0
(-1645 3605);
DISPLAY 0.872340 (-1645 3605);
PAINT GREEN (-1645 3605);
DISPLAY INVISIBLE (-1645 3605);
FORCEPROP 1 LAST OFFPAGE TRUE
J 0
(-1275 3575);
DISPLAY 0.872340 (-1275 3575);
PAINT GREEN (-1275 3575);
DISPLAY INVISIBLE (-1275 3575);
FORCEPROP 2 LAST CDS_LIB mstr_standard
J 0
(-1600 3700);
PAINT ORANGE (-1600 3700);
DISPLAY INVISIBLE (-1600 3700);
FORCEPROP 2 LAST PATH I47
J 0
(-1275 3750);
DISPLAY 1.021277 (-1275 3750);
PAINT ORANGE (-1275 3750);
DISPLAY INVISIBLE (-1275 3750);
FORCEADD OFFPAGE..2
(-1600 3800);
FORCEPROP 2 LAST $XR0 120 
J 0
(-1411 3800);
DISPLAY 0.638298 (-1411 3800);
PAINT MONO (-1411 3800);
FORCEPROP 2 LAST $XR1 155 
J 0
(-1291 3800);
DISPLAY 0.638298 (-1291 3800);
PAINT MONO (-1291 3800);
FORCEPROP 1 LAST COMMENT_BODY TRUE
J 0
(-1645 3705);
DISPLAY 0.872340 (-1645 3705);
PAINT GREEN (-1645 3705);
DISPLAY INVISIBLE (-1645 3705);
FORCEPROP 1 LAST OFFPAGE TRUE
J 0
(-1275 3675);
DISPLAY 0.872340 (-1275 3675);
PAINT GREEN (-1275 3675);
DISPLAY INVISIBLE (-1275 3675);
FORCEPROP 2 LAST CDS_LIB mstr_standard
J 0
(-1600 3800);
PAINT ORANGE (-1600 3800);
DISPLAY INVISIBLE (-1600 3800);
FORCEPROP 2 LAST PATH I48
J 0
(-1275 3850);
DISPLAY 1.021277 (-1275 3850);
PAINT ORANGE (-1275 3850);
DISPLAY INVISIBLE (-1275 3850);
FORCEADD OFFPAGE..2
(-1600 4050);
FORCEPROP 2 LAST $XR1 155 
J 0
(-1291 4050);
DISPLAY 0.638298 (-1291 4050);
PAINT MONO (-1291 4050);
FORCEPROP 2 LAST $XR0 120 
J 0
(-1411 4050);
DISPLAY 0.638298 (-1411 4050);
PAINT MONO (-1411 4050);
FORCEPROP 1 LAST COMMENT_BODY TRUE
J 0
(-1645 3955);
DISPLAY 0.872340 (-1645 3955);
PAINT GREEN (-1645 3955);
DISPLAY INVISIBLE (-1645 3955);
FORCEPROP 1 LAST OFFPAGE TRUE
J 0
(-1275 3925);
DISPLAY 0.872340 (-1275 3925);
PAINT GREEN (-1275 3925);
DISPLAY INVISIBLE (-1275 3925);
FORCEPROP 2 LAST CDS_LIB mstr_standard
J 0
(-1600 4050);
PAINT ORANGE (-1600 4050);
DISPLAY INVISIBLE (-1600 4050);
FORCEPROP 2 LAST PATH I49
J 0
(-1275 4100);
DISPLAY 1.021277 (-1275 4100);
PAINT ORANGE (-1275 4100);
DISPLAY INVISIBLE (-1275 4100);
FORCEADD OFFPAGE..1
(-6200 4650);
FORCEPROP 2 LAST $XR0 119 
J 0
(-6452 4650);
DISPLAY 0.638298 (-6452 4650);
PAINT MONO (-6452 4650);
FORCEPROP 2 LAST $XR1 133 
J 0
(-6572 4650);
DISPLAY 0.638298 (-6572 4650);
PAINT MONO (-6572 4650);
FORCEPROP 2 LAST CDS_LIB mstr_standard
J 0
(-6200 4650);
PAINT MONO (-6200 4650);
DISPLAY INVISIBLE (-6200 4650);
FORCEPROP 2 LAST PATH I5
J 0
(-6150 4725);
DISPLAY 1.021277 (-6150 4725);
PAINT ORANGE (-6150 4725);
DISPLAY INVISIBLE (-6150 4725);
FORCEPROP 2 LAST BOM_COST SM_CONTROLLER
J 0
(-5750 4700);
PAINT MONO (-5750 4700);
DISPLAY INVISIBLE (-5750 4700);
FORCEPROP 2 LAST ROOM BMC
J 0
(-6450 4725);
DISPLAY 1.361702 (-6450 4725);
PAINT ORANGE (-6450 4725);
DISPLAY INVISIBLE (-6450 4725);
FORCEPROP 1 LAST OFFPAGE TRUE
J 0
(-5875 4525);
DISPLAY 0.872340 (-5875 4525);
PAINT GREEN (-5875 4525);
DISPLAY INVISIBLE (-5875 4525);
FORCEPROP 1 LAST COMMENT_BODY TRUE
J 0
(-6075 4550);
DISPLAY 0.872340 (-6075 4550);
PAINT GREEN (-6075 4550);
DISPLAY INVISIBLE (-6075 4550);
FORCEADD RES..2
(-1750 4725);
FORCEPROP 1 LAST TOLERANCE 1%
J 0
(-1705 4750);
DISPLAY 0.617021 (-1705 4750);
PAINT SKYBLUE (-1705 4750);
FORCEPROP 1 LAST WATTAGE 1/16W
J 0
(-1710 4700);
DISPLAY 0.617021 (-1710 4700);
PAINT SKYBLUE (-1710 4700);
FORCEPROP 1 LAST MATERIAL CHIP
J 0
(-1710 4650);
DISPLAY 0.617021 (-1710 4650);
PAINT SKYBLUE (-1710 4650);
FORCEPROP 1 LAST PACK_TYPE 0402
J 0
(-1710 4550);
DISPLAY 0.617021 (-1710 4550);
PAINT SKYBLUE (-1710 4550);
FORCEPROP 1 LAST PART_NUMBER G21796-003
J 0
(-1710 4600);
DISPLAY 0.617021 (-1710 4600);
PAINT BLUE (-1710 4600);
FORCEPROP 1 LAST LOCATION R1U52
J 0
(-1705 4850);
DISPLAY 0.617021 (-1705 4850);
PAINT AQUA (-1705 4850);
FORCEPROP 1 LAST VALUE 1.5K
J 0
(-1705 4800);
DISPLAY 0.617021 (-1705 4800);
PAINT SKYBLUE (-1705 4800);
FORCEPROP 1 LAST PATH I51
J 0
(-1700 4900);
DISPLAY 0.978723 (-1700 4900);
PAINT WHITE (-1700 4900);
DISPLAY INVISIBLE (-1700 4900);
FORCEPROP 0 LAST BOM_COST SM_CONTROLLER
J 0
(-1700 5050);
DISPLAY 1.021277 (-1700 5050);
PAINT ORANGE (-1700 5050);
DISPLAY INVISIBLE (-1700 5050);
FORCEPROP 2 LAST CDS_SEC 1
J 0
(-1700 4950);
PAINT MONO (-1700 4950);
DISPLAY INVISIBLE (-1700 4950);
FORCEPROP 2 LAST $SEC 1
J 0
(-1700 4950);
PAINT MONO (-1700 4950);
DISPLAY INVISIBLE (-1700 4950);
FORCEPROP 0 LAST ROOM BMC
J 0
(-1700 4950);
DISPLAY 1.021277 (-1700 4950);
PAINT ORANGE (-1700 4950);
DISPLAY INVISIBLE (-1700 4950);
FORCEPROP 2 LAST CDS_LOCATION R1U52
J 0
(-1705 4850);
DISPLAY 0.617021 (-1705 4850);
PAINT AQUA (-1705 4850);
DISPLAY INVISIBLE (-1705 4850);
FORCEPROP 1 LASTPIN (-1750 4825) $PN 1
J 0
(-1745 4787);
DISPLAY 0.787234 (-1745 4787);
PAINT ORANGE (-1745 4787);
DISPLAY INVISIBLE (-1745 4787);
FORCEPROP 2 LAST CDS_LIB mstr_discrete
J 0
(-1750 4725);
PAINT ORANGE (-1750 4725);
DISPLAY INVISIBLE (-1750 4725);
FORCEPROP 1 LASTPIN (-1750 4625) $PN 2
J 0
(-1745 4635);
DISPLAY 0.787234 (-1745 4635);
PAINT ORANGE (-1745 4635);
DISPLAY INVISIBLE (-1745 4635);
FORCEADD P3V3_STBY..1
(-1750 4900);
FORCEPROP 3 LASTPIN (-1750 4850) SIG_NAME P3V3_STBY\g
J 0
(-1740 4860);
DISPLAY 0.659574 (-1740 4860);
PAINT MONO (-1740 4860);
DISPLAY INVISIBLE (-1740 4860);
FORCEPROP 1 LAST HDL_POWER P3V3_STBY
J 0
(-2050 4775);
DISPLAY 0.872340 (-2050 4775);
PAINT ORANGE (-2050 4775);
DISPLAY INVISIBLE (-2050 4775);
FORCEPROP 1 LAST BODY_TYPE PLUMBING
J 0
(-1795 4857);
DISPLAY 0.340426 (-1795 4857);
PAINT GREEN (-1795 4857);
DISPLAY INVISIBLE (-1795 4857);
FORCEPROP 1 LAST VOLTAGE 3.3V
J 0
(-1795 4857);
DISPLAY 0.340426 (-1795 4857);
PAINT SKYBLUE (-1795 4857);
DISPLAY INVISIBLE (-1795 4857);
FORCEPROP 2 LAST CDS_LIB mstr_symbols
J 0
(-1750 4900);
PAINT ORANGE (-1750 4900);
DISPLAY INVISIBLE (-1750 4900);
FORCEPROP 1 LAST SIZE 1B
J 0
(-1705 4922);
DISPLAY 0.340426 (-1705 4922);
PAINT GREEN (-1705 4922);
DISPLAY INVISIBLE (-1705 4922);
FORCEPROP 1 LAST PATH I52
J 0
(-1705 4902);
DISPLAY 0.340426 (-1705 4902);
PAINT GREEN (-1705 4902);
DISPLAY INVISIBLE (-1705 4902);
FORCEADD OFFPAGE..2
(-1850 2650);
FORCEPROP 2 LAST $XR0 149 
J 0
(-1661 2650);
DISPLAY 0.638298 (-1661 2650);
PAINT MONO (-1661 2650);
FORCEPROP 1 LAST COMMENT_BODY TRUE
J 0
(-1895 2555);
DISPLAY 0.872340 (-1895 2555);
PAINT GREEN (-1895 2555);
DISPLAY INVISIBLE (-1895 2555);
FORCEPROP 1 LAST OFFPAGE TRUE
J 0
(-1525 2525);
DISPLAY 0.872340 (-1525 2525);
PAINT GREEN (-1525 2525);
DISPLAY INVISIBLE (-1525 2525);
FORCEPROP 2 LAST PATH I54
J 0
(-1675 2725);
DISPLAY 1.021277 (-1675 2725);
PAINT ORANGE (-1675 2725);
DISPLAY INVISIBLE (-1675 2725);
FORCEPROP 2 LAST CDS_LIB mstr_standard
J 0
(-1850 2650);
PAINT MONO (-1850 2650);
DISPLAY INVISIBLE (-1850 2650);
FORCEADD OFFPAGE..2
(-1850 2600);
FORCEPROP 2 LAST $XR0 149 
J 0
(-1661 2600);
DISPLAY 0.638298 (-1661 2600);
PAINT MONO (-1661 2600);
FORCEPROP 1 LAST COMMENT_BODY TRUE
J 0
(-1895 2505);
DISPLAY 0.872340 (-1895 2505);
PAINT GREEN (-1895 2505);
DISPLAY INVISIBLE (-1895 2505);
FORCEPROP 1 LAST OFFPAGE TRUE
J 0
(-1525 2475);
DISPLAY 0.872340 (-1525 2475);
PAINT GREEN (-1525 2475);
DISPLAY INVISIBLE (-1525 2475);
FORCEPROP 2 LAST CDS_LIB mstr_standard
J 0
(-1850 2600);
PAINT MONO (-1850 2600);
DISPLAY INVISIBLE (-1850 2600);
FORCEPROP 2 LAST PATH I55
J 0
(-1675 2675);
DISPLAY 1.021277 (-1675 2675);
PAINT ORANGE (-1675 2675);
DISPLAY INVISIBLE (-1675 2675);
FORCEADD OFFPAGE..4
(-300 1525);
FORCEPROP 2 LAST $XR1 120 
J 0
(6 1525);
DISPLAY 0.638298 (6 1525);
PAINT MONO (6 1525);
FORCEPROP 2 LAST $XR0 190 
J 0
(-114 1525);
DISPLAY 0.638298 (-114 1525);
PAINT MONO (-114 1525);
FORCEPROP 1 LAST COMMENT_BODY TRUE
J 0
(-325 1425);
DISPLAY 0.872340 (-325 1425);
PAINT GREEN (-325 1425);
DISPLAY INVISIBLE (-325 1425);
FORCEPROP 1 LAST OFFPAGE TRUE
J 0
(25 1400);
DISPLAY 0.872340 (25 1400);
PAINT GREEN (25 1400);
DISPLAY INVISIBLE (25 1400);
FORCEPROP 2 LAST PATH I56
J 0
(25 1575);
DISPLAY 1.021277 (25 1575);
PAINT ORANGE (25 1575);
DISPLAY INVISIBLE (25 1575);
FORCEPROP 2 LAST CDS_LIB mstr_standard
J 0
(-300 1525);
PAINT MONO (-300 1525);
DISPLAY INVISIBLE (-300 1525);
FORCEADD OFFPAGE..4
(-1650 2000);
FORCEPROP 2 LAST $XR1 120 
J 0
(-1344 2000);
DISPLAY 0.638298 (-1344 2000);
PAINT MONO (-1344 2000);
FORCEPROP 2 LAST $XR0 191 
J 0
(-1464 2000);
DISPLAY 0.638298 (-1464 2000);
PAINT MONO (-1464 2000);
FORCEPROP 1 LAST COMMENT_BODY TRUE
J 0
(-1675 1900);
DISPLAY 0.872340 (-1675 1900);
PAINT GREEN (-1675 1900);
DISPLAY INVISIBLE (-1675 1900);
FORCEPROP 1 LAST OFFPAGE TRUE
J 0
(-1325 1875);
DISPLAY 0.872340 (-1325 1875);
PAINT GREEN (-1325 1875);
DISPLAY INVISIBLE (-1325 1875);
FORCEPROP 2 LAST PATH I57
J 0
(-1475 2075);
DISPLAY 1.021277 (-1475 2075);
PAINT ORANGE (-1475 2075);
DISPLAY INVISIBLE (-1475 2075);
FORCEPROP 2 LAST CDS_LIB mstr_standard
J 0
(-1650 2000);
PAINT MONO (-1650 2000);
DISPLAY INVISIBLE (-1650 2000);
FORCEADD OFFPAGE..2
(-1650 1900);
FORCEPROP 2 LAST $XR0 154 
J 0
(-1461 1900);
DISPLAY 0.638298 (-1461 1900);
PAINT MONO (-1461 1900);
FORCEPROP 1 LAST COMMENT_BODY TRUE
J 0
(-1695 1805);
DISPLAY 0.872340 (-1695 1805);
PAINT GREEN (-1695 1805);
DISPLAY INVISIBLE (-1695 1805);
FORCEPROP 1 LAST OFFPAGE TRUE
J 0
(-1325 1775);
DISPLAY 0.872340 (-1325 1775);
PAINT GREEN (-1325 1775);
DISPLAY INVISIBLE (-1325 1775);
FORCEPROP 2 LAST PATH I59
J 0
(-1475 1975);
DISPLAY 1.021277 (-1475 1975);
PAINT ORANGE (-1475 1975);
DISPLAY INVISIBLE (-1475 1975);
FORCEPROP 2 LAST CDS_LIB mstr_standard
J 0
(-1650 1900);
PAINT MONO (-1650 1900);
DISPLAY INVISIBLE (-1650 1900);
FORCEADD OFFPAGE..2
(-1650 1950);
FORCEPROP 2 LAST $XR0 246 
J 0
(-1461 1950);
DISPLAY 0.638298 (-1461 1950);
PAINT MONO (-1461 1950);
FORCEPROP 1 LAST COMMENT_BODY TRUE
J 0
(-1695 1855);
DISPLAY 0.872340 (-1695 1855);
PAINT GREEN (-1695 1855);
DISPLAY INVISIBLE (-1695 1855);
FORCEPROP 1 LAST OFFPAGE TRUE
J 0
(-1325 1825);
DISPLAY 0.872340 (-1325 1825);
PAINT GREEN (-1325 1825);
DISPLAY INVISIBLE (-1325 1825);
FORCEPROP 2 LAST PATH I60
J 0
(-1475 2025);
DISPLAY 1.021277 (-1475 2025);
PAINT ORANGE (-1475 2025);
DISPLAY INVISIBLE (-1475 2025);
FORCEPROP 2 LAST CDS_LIB mstr_standard
J 0
(-1650 1950);
PAINT MONO (-1650 1950);
DISPLAY INVISIBLE (-1650 1950);
FORCEADD OFFPAGE..4
(-1650 1800);
FORCEPROP 2 LAST $XR0 154 
J 0
(-1464 1800);
DISPLAY 0.638298 (-1464 1800);
PAINT MONO (-1464 1800);
FORCEPROP 1 LAST COMMENT_BODY TRUE
J 0
(-1675 1700);
DISPLAY 0.872340 (-1675 1700);
PAINT GREEN (-1675 1700);
DISPLAY INVISIBLE (-1675 1700);
FORCEPROP 1 LAST OFFPAGE TRUE
J 0
(-1325 1675);
DISPLAY 0.872340 (-1325 1675);
PAINT GREEN (-1325 1675);
DISPLAY INVISIBLE (-1325 1675);
FORCEPROP 2 LAST PATH I61
J 0
(-1475 1875);
DISPLAY 1.021277 (-1475 1875);
PAINT ORANGE (-1475 1875);
DISPLAY INVISIBLE (-1475 1875);
FORCEPROP 2 LAST CDS_LIB mstr_standard
J 0
(-1650 1800);
PAINT MONO (-1650 1800);
DISPLAY INVISIBLE (-1650 1800);
FORCEADD OFFPAGE..2
(-1650 1850);
FORCEPROP 2 LAST $XR0 154 
J 0
(-1461 1850);
DISPLAY 0.638298 (-1461 1850);
PAINT MONO (-1461 1850);
FORCEPROP 1 LAST COMMENT_BODY TRUE
J 0
(-1695 1755);
DISPLAY 0.872340 (-1695 1755);
PAINT GREEN (-1695 1755);
DISPLAY INVISIBLE (-1695 1755);
FORCEPROP 1 LAST OFFPAGE TRUE
J 0
(-1325 1725);
DISPLAY 0.872340 (-1325 1725);
PAINT GREEN (-1325 1725);
DISPLAY INVISIBLE (-1325 1725);
FORCEPROP 2 LAST PATH I62
J 0
(-1475 1925);
DISPLAY 1.021277 (-1475 1925);
PAINT ORANGE (-1475 1925);
DISPLAY INVISIBLE (-1475 1925);
FORCEPROP 2 LAST CDS_LIB mstr_standard
J 0
(-1650 1850);
PAINT MONO (-1650 1850);
DISPLAY INVISIBLE (-1650 1850);
FORCEADD OFFPAGE..2
(-1650 1650);
FORCEPROP 2 LAST $XR1 ?
J 0
(-1341 1650);
DISPLAY 0.638298 (-1341 1650);
PAINT MONO (-1341 1650);
FORCEPROP 2 LAST $XR0 142 
J 0
(-1461 1650);
DISPLAY 0.638298 (-1461 1650);
PAINT MONO (-1461 1650);
FORCEPROP 1 LAST COMMENT_BODY TRUE
J 0
(-1695 1555);
DISPLAY 0.872340 (-1695 1555);
PAINT GREEN (-1695 1555);
DISPLAY INVISIBLE (-1695 1555);
FORCEPROP 1 LAST OFFPAGE TRUE
J 0
(-1325 1525);
DISPLAY 0.872340 (-1325 1525);
PAINT GREEN (-1325 1525);
DISPLAY INVISIBLE (-1325 1525);
FORCEPROP 2 LAST PATH I63
J 0
(-1325 1700);
DISPLAY 1.021277 (-1325 1700);
PAINT ORANGE (-1325 1700);
DISPLAY INVISIBLE (-1325 1700);
FORCEPROP 2 LAST CDS_LIB mstr_standard
J 0
(-1650 1650);
PAINT MONO (-1650 1650);
DISPLAY INVISIBLE (-1650 1650);
FORCEADD RES..1
(-1275 1525);
FORCEPROP 1 LAST VALUE 33.2
J 2
(-1425 1500);
DISPLAY 0.617021 (-1425 1500);
PAINT SKYBLUE (-1425 1500);
FORCEPROP 1 LAST TOLERANCE 1%
J 0
(-1150 1525);
DISPLAY 0.617021 (-1150 1525);
PAINT SKYBLUE (-1150 1525);
FORCEPROP 1 LAST LOCATION R25W70
J 0
(-1525 1550);
DISPLAY 0.617021 (-1525 1550);
PAINT AQUA (-1525 1550);
FORCEPROP 1 LASTPIN (-1375 1525) $PN 1
J 0
(-1363 1537);
DISPLAY 0.617021 (-1363 1537);
PAINT ORANGE (-1363 1537);
FORCEPROP 1 LAST PACK_TYPE 0402
J 0
(-1150 1450);
DISPLAY 0.617021 (-1150 1450);
PAINT SKYBLUE (-1150 1450);
FORCEPROP 1 LAST PART_NUMBER G21796-074
J 0
(-1475 1450);
DISPLAY 0.617021 (-1475 1450);
PAINT BLUE (-1475 1450);
FORCEPROP 1 LAST MATERIAL CHIP
J 0
(-1325 1475);
DISPLAY 0.617021 (-1325 1475);
PAINT SKYBLUE (-1325 1475);
FORCEPROP 1 LASTPIN (-1175 1525) $PN 2
J 0
(-1213 1537);
DISPLAY 0.617021 (-1213 1537);
PAINT ORANGE (-1213 1537);
FORCEPROP 1 LAST WATTAGE 1/16W
J 2
(-1200 1575);
DISPLAY 0.617021 (-1200 1575);
PAINT SKYBLUE (-1200 1575);
FORCEPROP 1 LAST PATH I64
J 0
(-1325 1675);
DISPLAY 0.978723 (-1325 1675);
PAINT WHITE (-1325 1675);
DISPLAY INVISIBLE (-1325 1675);
FORCEPROP 0 LAST CDS_SEC 1
J 0
(-1325 1675);
PAINT MONO (-1325 1675);
DISPLAY INVISIBLE (-1325 1675);
FORCEPROP 2 LAST SEC 1
J 0
(-1325 1725);
DISPLAY 0.680851 (-1325 1725);
PAINT MONO (-1325 1725);
DISPLAY INVISIBLE (-1325 1725);
FORCEPROP 2 LAST SEC_TYPE 0402
J 0
(-1325 1725);
DISPLAY 1.021277 (-1325 1725);
PAINT ORANGE (-1325 1725);
DISPLAY INVISIBLE (-1325 1725);
FORCEPROP 0 LAST BOM_COST SM_CONTROLLER
J 0
(-1325 1725);
DISPLAY 1.021277 (-1325 1725);
PAINT ORANGE (-1325 1725);
DISPLAY INVISIBLE (-1325 1725);
FORCEPROP 0 LAST ROOM BMC
J 0
(-1325 1675);
DISPLAY 1.021277 (-1325 1675);
PAINT ORANGE (-1325 1675);
DISPLAY INVISIBLE (-1325 1675);
FORCEPROP 2 LAST CDS_LIB mstr_discrete
J 0
(-1275 1525);
PAINT ORANGE (-1275 1525);
DISPLAY INVISIBLE (-1275 1525);
FORCEPROP 2 LAST CDS_LOCATION R25W70
J 0
(-1825 1525);
DISPLAY 0.617021 (-1825 1525);
PAINT AQUA (-1825 1525);
DISPLAY INVISIBLE (-1825 1525);
FORCEADD RES..2
(-1800 1100);
FORCEPROP 1 LAST PACK_TYPE 0402
J 0
(-1760 925);
DISPLAY 0.617021 (-1760 925);
PAINT SKYBLUE (-1760 925);
FORCEPROP 1 LAST MATERIAL CHIP
J 0
(-1760 1025);
DISPLAY 0.617021 (-1760 1025);
PAINT SKYBLUE (-1760 1025);
FORCEPROP 1 LAST TOLERANCE 1%
J 0
(-1755 1125);
DISPLAY 0.617021 (-1755 1125);
PAINT SKYBLUE (-1755 1125);
FORCEPROP 1 LAST VALUE 100.0K
J 0
(-1755 1175);
DISPLAY 0.617021 (-1755 1175);
PAINT SKYBLUE (-1755 1175);
FORCEPROP 1 LAST LOCATION R25W63
J 0
(-1755 1225);
DISPLAY 0.617021 (-1755 1225);
PAINT AQUA (-1755 1225);
FORCEPROP 1 LASTPIN (-1800 1200) $PN 1
J 0
(-1795 1162);
DISPLAY 0.617021 (-1795 1162);
PAINT ORANGE (-1795 1162);
FORCEPROP 1 LASTPIN (-1800 1000) $PN 2
J 0
(-1795 1010);
DISPLAY 0.617021 (-1795 1010);
PAINT ORANGE (-1795 1010);
FORCEPROP 1 LAST PART_NUMBER G21796-010
J 0
(-1760 975);
DISPLAY 0.617021 (-1760 975);
PAINT BLUE (-1760 975);
FORCEPROP 1 LAST WATTAGE 1/16W
J 0
(-1760 1075);
DISPLAY 0.617021 (-1760 1075);
PAINT SKYBLUE (-1760 1075);
FORCEPROP 1 LAST PATH I65
J 0
(-1750 1275);
DISPLAY 0.978723 (-1750 1275);
PAINT WHITE (-1750 1275);
DISPLAY INVISIBLE (-1750 1275);
FORCEPROP 0 LAST ROOM BMC
J 0
(-1750 1325);
DISPLAY 0.617021 (-1750 1325);
PAINT ORANGE (-1750 1325);
DISPLAY INVISIBLE (-1750 1325);
FORCEPROP 0 LAST BOM_COST SM_CONTROLLER
J 0
(-1750 1425);
DISPLAY 1.021277 (-1750 1425);
PAINT ORANGE (-1750 1425);
DISPLAY INVISIBLE (-1750 1425);
FORCEPROP 2 LAST SEC_TYPE 0402
J 0
(-1750 1325);
DISPLAY 1.021277 (-1750 1325);
PAINT ORANGE (-1750 1325);
DISPLAY INVISIBLE (-1750 1325);
FORCEPROP 2 LAST SEC 1
J 0
(-1750 1325);
DISPLAY 0.680851 (-1750 1325);
PAINT MONO (-1750 1325);
DISPLAY INVISIBLE (-1750 1325);
FORCEPROP 2 LAST CDS_LIB mstr_discrete
J 0
(-1800 1100);
PAINT ORANGE (-1800 1100);
DISPLAY INVISIBLE (-1800 1100);
FORCEPROP 0 LAST CDS_SEC 1
J 0
(-1750 1275);
PAINT MONO (-1750 1275);
DISPLAY INVISIBLE (-1750 1275);
FORCEPROP 2 LAST CDS_LOCATION R25W63
J 0
(-1755 1225);
DISPLAY 0.617021 (-1755 1225);
PAINT AQUA (-1755 1225);
DISPLAY INVISIBLE (-1755 1225);
FORCEADD GND..1
(-1800 825);
FORCEPROP 3 LASTPIN (-1800 875) SIG_NAME GND\g
J 0
(-1790 885);
DISPLAY 0.659574 (-1790 885);
PAINT MONO (-1790 885);
DISPLAY INVISIBLE (-1790 885);
FORCEPROP 1 LAST HDL_POWER GND
J 0
(-1800 975);
DISPLAY 0.872340 (-1800 975);
PAINT GREEN (-1800 975);
DISPLAY INVISIBLE (-1800 975);
FORCEPROP 1 LAST BODY_TYPE PLUMBING
J 0
(-1845 782);
DISPLAY 0.340426 (-1845 782);
PAINT GREEN (-1845 782);
DISPLAY INVISIBLE (-1845 782);
FORCEPROP 1 LAST PATH I66
J 0
(-1725 825);
DISPLAY 0.872340 (-1725 825);
PAINT AQUA (-1725 825);
DISPLAY INVISIBLE (-1725 825);
FORCEPROP 1 LAST SIZE 1B
J 0
(-1725 775);
DISPLAY 0.872340 (-1725 775);
PAINT AQUA (-1725 775);
DISPLAY INVISIBLE (-1725 775);
FORCEPROP 1 LAST VOLTAGE 0.0V
J 0
(-1845 782);
DISPLAY 0.340426 (-1845 782);
PAINT SKYBLUE (-1845 782);
DISPLAY INVISIBLE (-1845 782);
FORCEPROP 2 LAST CDS_LIB mstr_symbols
J 0
(-1800 825);
PAINT ORANGE (-1800 825);
DISPLAY INVISIBLE (-1800 825);
FORCEADD RES..1
(-6225 2350);
FORCEPROP 1 LASTPIN (-6125 2350) $PN 2
J 0
(-6163 2362);
DISPLAY 0.617021 (-6163 2362);
PAINT ORANGE (-6163 2362);
FORCEPROP 1 LASTPIN (-6325 2350) $PN 1
J 0
(-6313 2362);
DISPLAY 0.617021 (-6313 2362);
PAINT ORANGE (-6313 2362);
FORCEPROP 1 LAST TOLERANCE 1%
J 0
(-5975 2300);
DISPLAY 0.617021 (-5975 2300);
PAINT SKYBLUE (-5975 2300);
FORCEPROP 1 LAST MATERIAL CHIP
J 0
(-5875 2300);
DISPLAY 0.617021 (-5875 2300);
PAINT SKYBLUE (-5875 2300);
FORCEPROP 1 LAST VALUE 33.2
J 2
(-6025 2300);
DISPLAY 0.617021 (-6025 2300);
PAINT SKYBLUE (-6025 2300);
FORCEPROP 1 LAST LOCATION R25W81
J 0
(-6300 2300);
DISPLAY 0.617021 (-6300 2300);
PAINT AQUA (-6300 2300);
FORCEPROP 1 LAST PATH I67
J 0
(-6275 2500);
DISPLAY 0.978723 (-6275 2500);
PAINT WHITE (-6275 2500);
DISPLAY INVISIBLE (-6275 2500);
FORCEPROP 0 LAST BOM_COST SM_CONTROLLER
J 0
(-6025 2450);
DISPLAY 1.021277 (-6025 2450);
PAINT ORANGE (-6025 2450);
DISPLAY INVISIBLE (-6025 2450);
FORCEPROP 0 LAST ROOM BMC
J 0
(-6025 2400);
DISPLAY 1.021277 (-6025 2400);
PAINT ORANGE (-6025 2400);
DISPLAY INVISIBLE (-6025 2400);
FORCEPROP 1 LAST PACK_TYPE 0402
J 0
(-5975 2200);
DISPLAY 0.978723 (-5975 2200);
PAINT SKYBLUE (-5975 2200);
DISPLAY INVISIBLE (-5975 2200);
FORCEPROP 2 LAST SEC 1
J 0
(-6275 2550);
PAINT MONO (-6275 2550);
DISPLAY INVISIBLE (-6275 2550);
FORCEPROP 2 LAST SEC_TYPE 0402
J 0
(-6275 2550);
DISPLAY 1.021277 (-6275 2550);
PAINT ORANGE (-6275 2550);
DISPLAY INVISIBLE (-6275 2550);
FORCEPROP 1 LAST PART_NUMBER G21796-074
J 0
(-6275 2450);
DISPLAY 0.978723 (-6275 2450);
PAINT BLUE (-6275 2450);
DISPLAY INVISIBLE (-6275 2450);
FORCEPROP 2 LAST CDS_LIB mstr_discrete
J 0
(-6225 2350);
PAINT ORANGE (-6225 2350);
DISPLAY INVISIBLE (-6225 2350);
FORCEPROP 1 LAST WATTAGE 1/16W
J 2
(-6250 2200);
DISPLAY 0.978723 (-6250 2200);
PAINT SKYBLUE (-6250 2200);
DISPLAY INVISIBLE (-6250 2200);
FORCEPROP 2 LAST CDS_LOCATION R25W81
J 0
(-6300 2275);
DISPLAY 0.617021 (-6300 2275);
PAINT AQUA (-6300 2275);
DISPLAY INVISIBLE (-6300 2275);
FORCEADD RES..1
(-6300 2500);
FORCEPROP 1 LASTPIN (-6400 2500) $PN 1
J 0
(-6388 2512);
DISPLAY 0.617021 (-6388 2512);
PAINT ORANGE (-6388 2512);
FORCEPROP 1 LASTPIN (-6200 2500) $PN 2
J 0
(-6238 2512);
DISPLAY 0.617021 (-6238 2512);
PAINT ORANGE (-6238 2512);
FORCEPROP 1 LAST VALUE 33.2
J 2
(-6125 2500);
DISPLAY 0.617021 (-6125 2500);
PAINT SKYBLUE (-6125 2500);
FORCEPROP 1 LAST MATERIAL CHIP
J 0
(-6475 2500);
DISPLAY 0.617021 (-6475 2500);
PAINT SKYBLUE (-6475 2500);
FORCEPROP 1 LAST LOCATION R25W82
J 0
(-6375 2550);
DISPLAY 0.617021 (-6375 2550);
PAINT AQUA (-6375 2550);
FORCEPROP 1 LAST TOLERANCE 1%
J 0
(-6100 2500);
DISPLAY 0.617021 (-6100 2500);
PAINT SKYBLUE (-6100 2500);
FORCEPROP 1 LAST PATH I68
J 0
(-6350 2650);
DISPLAY 0.978723 (-6350 2650);
PAINT WHITE (-6350 2650);
DISPLAY INVISIBLE (-6350 2650);
FORCEPROP 1 LAST PACK_TYPE 0402
J 0
(-6050 2350);
DISPLAY 0.978723 (-6050 2350);
PAINT SKYBLUE (-6050 2350);
DISPLAY INVISIBLE (-6050 2350);
FORCEPROP 2 LAST SEC 1
J 0
(-6350 2700);
PAINT MONO (-6350 2700);
DISPLAY INVISIBLE (-6350 2700);
FORCEPROP 2 LAST SEC_TYPE 0402
J 0
(-6350 2700);
DISPLAY 1.021277 (-6350 2700);
PAINT ORANGE (-6350 2700);
DISPLAY INVISIBLE (-6350 2700);
FORCEPROP 0 LAST BOM_COST SM_CONTROLLER
J 0
(-6350 2650);
DISPLAY 1.021277 (-6350 2650);
PAINT ORANGE (-6350 2650);
DISPLAY INVISIBLE (-6350 2650);
FORCEPROP 0 LAST ROOM BMC
J 0
(-6350 2600);
DISPLAY 1.021277 (-6350 2600);
PAINT ORANGE (-6350 2600);
DISPLAY INVISIBLE (-6350 2600);
FORCEPROP 1 LAST PART_NUMBER G21796-074
J 0
(-6350 2600);
DISPLAY 0.978723 (-6350 2600);
PAINT BLUE (-6350 2600);
DISPLAY INVISIBLE (-6350 2600);
FORCEPROP 2 LAST CDS_LIB mstr_discrete
J 0
(-6300 2500);
PAINT ORANGE (-6300 2500);
DISPLAY INVISIBLE (-6300 2500);
FORCEPROP 1 LAST WATTAGE 1/16W
J 2
(-6325 2350);
DISPLAY 0.978723 (-6325 2350);
PAINT SKYBLUE (-6325 2350);
DISPLAY INVISIBLE (-6325 2350);
FORCEPROP 2 LAST CDS_LOCATION R25W82
J 0
(-6350 2550);
DISPLAY 0.617021 (-6350 2550);
PAINT AQUA (-6350 2550);
DISPLAY INVISIBLE (-6350 2550);
FORCEADD RES..1
(-6550 2400);
FORCEPROP 1 LAST MATERIAL CHIP
J 0
(-6475 2300);
DISPLAY 0.617021 (-6475 2300);
PAINT SKYBLUE (-6475 2300);
FORCEPROP 1 LAST TOLERANCE 1.0%
J 0
(-6575 2300);
DISPLAY 0.617021 (-6575 2300);
PAINT SKYBLUE (-6575 2300);
FORCEPROP 1 LASTPIN (-6450 2400) $PN 2
J 0
(-6488 2412);
DISPLAY 0.617021 (-6488 2412);
PAINT ORANGE (-6488 2412);
FORCEPROP 1 LASTPIN (-6650 2400) $PN 1
J 0
(-6638 2412);
DISPLAY 0.617021 (-6638 2412);
PAINT ORANGE (-6638 2412);
FORCEPROP 1 LAST LOCATION R25W78
J 0
(-6625 2350);
DISPLAY 0.617021 (-6625 2350);
PAINT AQUA (-6625 2350);
FORCEPROP 1 LAST VALUE 22.1
J 2
(-6575 2300);
DISPLAY 0.617021 (-6575 2300);
PAINT SKYBLUE (-6575 2300);
FORCEPROP 1 LAST PATH I69
J 0
(-6600 2550);
DISPLAY 0.978723 (-6600 2550);
PAINT WHITE (-6600 2550);
DISPLAY INVISIBLE (-6600 2550);
FORCEPROP 0 LAST BOM_COST SM_CONTROLLER
J 0
(-6300 2625);
DISPLAY 1.021277 (-6300 2625);
PAINT ORANGE (-6300 2625);
DISPLAY INVISIBLE (-6300 2625);
FORCEPROP 0 LAST ROOM BMC
J 0
(-6300 2525);
DISPLAY 1.021277 (-6300 2525);
PAINT ORANGE (-6300 2525);
DISPLAY INVISIBLE (-6300 2525);
FORCEPROP 1 LAST PACK_TYPE 0402
J 0
(-6300 2250);
DISPLAY 0.978723 (-6300 2250);
PAINT SKYBLUE (-6300 2250);
DISPLAY INVISIBLE (-6300 2250);
FORCEPROP 2 LAST SEC 1
J 0
(-6600 2600);
DISPLAY 0.680851 (-6600 2600);
PAINT MONO (-6600 2600);
DISPLAY INVISIBLE (-6600 2600);
FORCEPROP 2 LAST SEC_TYPE 0402
J 0
(-6600 2600);
DISPLAY 1.021277 (-6600 2600);
PAINT ORANGE (-6600 2600);
DISPLAY INVISIBLE (-6600 2600);
FORCEPROP 1 LAST PART_NUMBER G21796-250
J 0
(-6600 2500);
DISPLAY 0.978723 (-6600 2500);
PAINT BLUE (-6600 2500);
DISPLAY INVISIBLE (-6600 2500);
FORCEPROP 2 LAST CDS_LIB mstr_discrete
J 0
(-6550 2400);
PAINT ORANGE (-6550 2400);
DISPLAY INVISIBLE (-6550 2400);
FORCEPROP 1 LAST WATTAGE 1/16W
J 2
(-6575 2250);
DISPLAY 0.978723 (-6575 2250);
PAINT SKYBLUE (-6575 2250);
DISPLAY INVISIBLE (-6575 2250);
FORCEPROP 2 LAST CDS_LOCATION R25W78
J 0
(-6575 2425);
DISPLAY 0.617021 (-6575 2425);
PAINT AQUA (-6575 2425);
DISPLAY INVISIBLE (-6575 2425);
FORCEADD RES..1
(-6425 1750);
FORCEPROP 1 LASTPIN (-6525 1750) $PN 1
J 0
(-6513 1762);
DISPLAY 0.617021 (-6513 1762);
PAINT ORANGE (-6513 1762);
FORCEPROP 1 LAST VALUE 0.0
J 2
(-6350 1800);
DISPLAY 0.617021 (-6350 1800);
PAINT SKYBLUE (-6350 1800);
FORCEPROP 1 LASTPIN (-6325 1750) $PN 2
J 0
(-6363 1762);
DISPLAY 0.617021 (-6363 1762);
PAINT ORANGE (-6363 1762);
FORCEPROP 1 LAST LOCATION R25W74
J 0
(-6625 1800);
DISPLAY 0.617021 (-6625 1800);
PAINT AQUA (-6625 1800);
FORCEPROP 1 LAST PACK_TYPE 0402
J 0
(-6425 1850);
DISPLAY 0.617021 (-6425 1850);
PAINT SKYBLUE (-6425 1850);
FORCEPROP 1 LAST PATH I70
J 0
(-6475 1900);
DISPLAY 0.978723 (-6475 1900);
PAINT WHITE (-6475 1900);
DISPLAY INVISIBLE (-6475 1900);
FORCEPROP 1 LAST PART_NUMBER G21497-005
J 0
(-6675 1825);
DISPLAY 0.617021 (-6675 1825);
PAINT BLUE (-6675 1825);
DISPLAY INVISIBLE (-6675 1825);
FORCEPROP 1 LAST WATTAGE 1/16W
J 2
(-6525 1775);
DISPLAY 0.617021 (-6525 1775);
PAINT SKYBLUE (-6525 1775);
DISPLAY INVISIBLE (-6525 1775);
FORCEPROP 1 LAST TOLERANCE 5%
J 0
(-6075 1775);
DISPLAY 0.617021 (-6075 1775);
PAINT SKYBLUE (-6075 1775);
DISPLAY INVISIBLE (-6075 1775);
FORCEPROP 1 LAST MATERIAL CHIP
J 0
(-6300 1775);
DISPLAY 0.617021 (-6300 1775);
PAINT SKYBLUE (-6300 1775);
DISPLAY INVISIBLE (-6300 1775);
FORCEPROP 2 LAST BOM_COST SM_CONTROLLER
J 0
(-6363 1802);
DISPLAY 0.787234 (-6363 1802);
PAINT SKYBLUE (-6363 1802);
DISPLAY INVISIBLE (-6363 1802);
FORCEPROP 2 LAST SEC 1
J 0
(-6475 1950);
DISPLAY 0.680851 (-6475 1950);
PAINT MONO (-6475 1950);
DISPLAY INVISIBLE (-6475 1950);
FORCEPROP 2 LAST SEC_TYPE 0402
J 0
(-6475 1950);
DISPLAY 1.021277 (-6475 1950);
PAINT ORANGE (-6475 1950);
DISPLAY INVISIBLE (-6475 1950);
FORCEPROP 0 LAST ROOM BMC
J 0
(-6475 1900);
DISPLAY 1.021277 (-6475 1900);
PAINT ORANGE (-6475 1900);
DISPLAY INVISIBLE (-6475 1900);
FORCEPROP 2 LAST CDS_LIB mstr_discrete
J 0
(-6425 1750);
PAINT ORANGE (-6425 1750);
DISPLAY INVISIBLE (-6425 1750);
FORCEPROP 0 LAST CDS_SEC 1
J 0
(-6475 1850);
PAINT MONO (-6475 1850);
DISPLAY INVISIBLE (-6475 1850);
FORCEPROP 2 LAST CDS_LOCATION R25W74
J 0
(-6475 1800);
DISPLAY 0.617021 (-6475 1800);
PAINT AQUA (-6475 1800);
DISPLAY INVISIBLE (-6475 1800);
FORCEADD RES..1
(-6425 1600);
FORCEPROP 1 LAST LOCATION R25W72
J 0
(-6675 1575);
DISPLAY 0.617021 (-6675 1575);
PAINT AQUA (-6675 1575);
FORCEPROP 1 LASTPIN (-6525 1600) $PN 1
J 0
(-6513 1612);
DISPLAY 0.617021 (-6513 1612);
PAINT ORANGE (-6513 1612);
FORCEPROP 1 LASTPIN (-6325 1600) $PN 2
J 0
(-6363 1612);
DISPLAY 0.617021 (-6363 1612);
PAINT ORANGE (-6363 1612);
FORCEPROP 1 LAST VALUE 33.2
J 2
(-6375 1625);
DISPLAY 0.617021 (-6375 1625);
PAINT SKYBLUE (-6375 1625);
FORCEPROP 1 LAST PACK_TYPE 0402
J 0
(-6375 1550);
DISPLAY 0.617021 (-6375 1550);
PAINT SKYBLUE (-6375 1550);
FORCEPROP 1 LAST PATH I71
J 0
(-6475 1750);
DISPLAY 0.978723 (-6475 1750);
PAINT WHITE (-6475 1750);
DISPLAY INVISIBLE (-6475 1750);
FORCEPROP 1 LAST PART_NUMBER G21796-074
J 0
(-6650 1700);
DISPLAY 0.617021 (-6650 1700);
PAINT BLUE (-6650 1700);
DISPLAY INVISIBLE (-6650 1700);
FORCEPROP 0 LAST CDS_SEC 1
J 0
(-6475 1750);
PAINT MONO (-6475 1750);
DISPLAY INVISIBLE (-6475 1750);
FORCEPROP 2 LAST CDS_LIB mstr_discrete
J 0
(-6425 1600);
PAINT ORANGE (-6425 1600);
DISPLAY INVISIBLE (-6425 1600);
FORCEPROP 0 LAST ROOM BMC
J 0
(-6475 1750);
DISPLAY 1.021277 (-6475 1750);
PAINT ORANGE (-6475 1750);
DISPLAY INVISIBLE (-6475 1750);
FORCEPROP 0 LAST SEC 1
J 0
(-6475 1750);
DISPLAY 0.680851 (-6475 1750);
PAINT MONO (-6475 1750);
DISPLAY INVISIBLE (-6475 1750);
FORCEPROP 2 LAST SEC_TYPE 0402
J 0
(-6475 1800);
DISPLAY 1.021277 (-6475 1800);
PAINT ORANGE (-6475 1800);
DISPLAY INVISIBLE (-6475 1800);
FORCEPROP 0 LAST BOM_COST SM_CONTROLLER
J 0
(-6475 1800);
DISPLAY 1.021277 (-6475 1800);
PAINT ORANGE (-6475 1800);
DISPLAY INVISIBLE (-6475 1800);
FORCEPROP 1 LAST MATERIAL CHIP
J 0
(-6325 1575);
DISPLAY 0.617021 (-6325 1575);
PAINT SKYBLUE (-6325 1575);
DISPLAY INVISIBLE (-6325 1575);
FORCEPROP 1 LAST WATTAGE 1/16W
J 2
(-6575 1575);
DISPLAY 0.617021 (-6575 1575);
PAINT SKYBLUE (-6575 1575);
DISPLAY INVISIBLE (-6575 1575);
FORCEPROP 1 LAST TOLERANCE 1%
J 0
(-6100 1575);
DISPLAY 0.617021 (-6100 1575);
PAINT SKYBLUE (-6100 1575);
DISPLAY INVISIBLE (-6100 1575);
FORCEPROP 2 LAST CDS_LOCATION R25W72
J 0
(-6475 1650);
DISPLAY 0.617021 (-6475 1650);
PAINT AQUA (-6475 1650);
DISPLAY INVISIBLE (-6475 1650);
FORCEADD RES..1
(-6425 1500);
FORCEPROP 1 LAST PACK_TYPE 0402
J 0
(-6350 1500);
DISPLAY 0.617021 (-6350 1500);
PAINT SKYBLUE (-6350 1500);
FORCEPROP 1 LAST LOCATION R25W71
J 0
(-6675 1500);
DISPLAY 0.617021 (-6675 1500);
PAINT AQUA (-6675 1500);
FORCEPROP 1 LAST VALUE 33.2
J 2
(-6375 1525);
DISPLAY 0.617021 (-6375 1525);
PAINT SKYBLUE (-6375 1525);
FORCEPROP 1 LAST PATH I72
J 0
(-6475 1650);
DISPLAY 0.978723 (-6475 1650);
PAINT WHITE (-6475 1650);
DISPLAY INVISIBLE (-6475 1650);
FORCEPROP 1 LAST WATTAGE 1/16W
J 2
(-6575 1450);
DISPLAY 0.617021 (-6575 1450);
PAINT SKYBLUE (-6575 1450);
DISPLAY INVISIBLE (-6575 1450);
FORCEPROP 1 LAST TOLERANCE 1%
J 0
(-6250 1475);
DISPLAY 0.617021 (-6250 1475);
PAINT SKYBLUE (-6250 1475);
DISPLAY INVISIBLE (-6250 1475);
FORCEPROP 1 LAST MATERIAL CHIP
J 0
(-6350 1475);
DISPLAY 0.617021 (-6350 1475);
PAINT SKYBLUE (-6350 1475);
DISPLAY INVISIBLE (-6350 1475);
FORCEPROP 1 LAST PART_NUMBER G21796-074
J 0
(-6500 1600);
DISPLAY 0.617021 (-6500 1600);
PAINT BLUE (-6500 1600);
DISPLAY INVISIBLE (-6500 1600);
FORCEPROP 2 LAST CDS_LIB mstr_discrete
J 0
(-6425 1500);
PAINT MONO (-6425 1500);
DISPLAY INVISIBLE (-6425 1500);
FORCEPROP 0 LAST BOM_COST SM_CONTROLLER
J 0
(-6475 1700);
DISPLAY 1.021277 (-6475 1700);
PAINT ORANGE (-6475 1700);
DISPLAY INVISIBLE (-6475 1700);
FORCEPROP 0 LAST ROOM BMC
J 0
(-6475 1650);
DISPLAY 1.021277 (-6475 1650);
PAINT ORANGE (-6475 1650);
DISPLAY INVISIBLE (-6475 1650);
FORCEPROP 1 LASTPIN (-6525 1500) $PN 1
J 0
(-6513 1512);
DISPLAY 0.787234 (-6513 1512);
PAINT ORANGE (-6513 1512);
DISPLAY INVISIBLE (-6513 1512);
FORCEPROP 1 LASTPIN (-6325 1500) $PN 2
J 0
(-6363 1512);
DISPLAY 0.787234 (-6363 1512);
PAINT ORANGE (-6363 1512);
DISPLAY INVISIBLE (-6363 1512);
FORCEADD RES..1
(-6425 1675);
FORCEPROP 1 LASTPIN (-6325 1675) $PN 2
J 0
(-6363 1687);
DISPLAY 0.617021 (-6363 1687);
PAINT ORANGE (-6363 1687);
FORCEPROP 1 LAST PACK_TYPE 0402
J 0
(-6375 1725);
DISPLAY 0.617021 (-6375 1725);
PAINT SKYBLUE (-6375 1725);
FORCEPROP 1 LASTPIN (-6525 1675) $PN 1
J 0
(-6513 1687);
DISPLAY 0.617021 (-6513 1687);
PAINT ORANGE (-6513 1687);
FORCEPROP 1 LAST VALUE 33.2
J 2
(-6375 1700);
DISPLAY 0.617021 (-6375 1700);
PAINT SKYBLUE (-6375 1700);
FORCEPROP 1 LAST LOCATION R25W73
J 0
(-6650 1700);
DISPLAY 0.617021 (-6650 1700);
PAINT AQUA (-6650 1700);
FORCEPROP 1 LAST PATH I73
J 0
(-6475 1825);
DISPLAY 0.978723 (-6475 1825);
PAINT WHITE (-6475 1825);
DISPLAY INVISIBLE (-6475 1825);
FORCEPROP 1 LAST TOLERANCE 1%
J 0
(-6100 1650);
DISPLAY 0.617021 (-6100 1650);
PAINT SKYBLUE (-6100 1650);
DISPLAY INVISIBLE (-6100 1650);
FORCEPROP 1 LAST MATERIAL CHIP
J 0
(-6350 1650);
DISPLAY 0.617021 (-6350 1650);
PAINT SKYBLUE (-6350 1650);
DISPLAY INVISIBLE (-6350 1650);
FORCEPROP 1 LAST PART_NUMBER G21796-074
J 0
(-6475 1775);
DISPLAY 0.617021 (-6475 1775);
PAINT BLUE (-6475 1775);
DISPLAY INVISIBLE (-6475 1775);
FORCEPROP 0 LAST CDS_SEC 1
J 0
(-6475 1825);
PAINT MONO (-6475 1825);
DISPLAY INVISIBLE (-6475 1825);
FORCEPROP 2 LAST CDS_LIB mstr_discrete
J 0
(-6425 1675);
PAINT ORANGE (-6425 1675);
DISPLAY INVISIBLE (-6425 1675);
FORCEPROP 0 LAST ROOM BMC
J 0
(-6475 1825);
DISPLAY 1.021277 (-6475 1825);
PAINT ORANGE (-6475 1825);
DISPLAY INVISIBLE (-6475 1825);
FORCEPROP 0 LAST SEC 1
J 0
(-6475 1825);
DISPLAY 0.680851 (-6475 1825);
PAINT MONO (-6475 1825);
DISPLAY INVISIBLE (-6475 1825);
FORCEPROP 0 LAST BOM_COST SM_CONTROLLER
J 0
(-6475 1875);
DISPLAY 1.021277 (-6475 1875);
PAINT ORANGE (-6475 1875);
DISPLAY INVISIBLE (-6475 1875);
FORCEPROP 2 LAST SEC_TYPE 0402
J 0
(-6475 1875);
DISPLAY 1.021277 (-6475 1875);
PAINT ORANGE (-6475 1875);
DISPLAY INVISIBLE (-6475 1875);
FORCEPROP 1 LAST WATTAGE 1/16W
J 2
(-6575 1650);
DISPLAY 0.617021 (-6575 1650);
PAINT SKYBLUE (-6575 1650);
DISPLAY INVISIBLE (-6575 1650);
FORCEPROP 2 LAST CDS_LOCATION R25W73
J 0
(-6475 1725);
DISPLAY 0.617021 (-6475 1725);
PAINT AQUA (-6475 1725);
DISPLAY INVISIBLE (-6475 1725);
FORCEADD RES..1
(-6500 1350);
FORCEPROP 1 LAST PACK_TYPE 0402
J 0
(-6425 1350);
DISPLAY 0.617021 (-6425 1350);
PAINT SKYBLUE (-6425 1350);
FORCEPROP 1 LAST VALUE 33.2
J 2
(-6550 1350);
DISPLAY 0.617021 (-6550 1350);
PAINT SKYBLUE (-6550 1350);
FORCEPROP 1 LAST LOCATION R3N24
J 0
(-6775 1350);
DISPLAY 0.617021 (-6775 1350);
PAINT AQUA (-6775 1350);
FORCEPROP 1 LAST PATH I74
J 0
(-6550 1500);
DISPLAY 0.978723 (-6550 1500);
PAINT WHITE (-6550 1500);
DISPLAY INVISIBLE (-6550 1500);
FORCEPROP 1 LAST WATTAGE 1/16W
J 2
(-6625 1325);
DISPLAY 0.617021 (-6625 1325);
PAINT SKYBLUE (-6625 1325);
DISPLAY INVISIBLE (-6625 1325);
FORCEPROP 1 LAST TOLERANCE 1%
J 0
(-6450 1325);
DISPLAY 0.617021 (-6450 1325);
PAINT SKYBLUE (-6450 1325);
DISPLAY INVISIBLE (-6450 1325);
FORCEPROP 1 LAST PART_NUMBER G21796-074
J 0
(-6725 1350);
DISPLAY 0.617021 (-6725 1350);
PAINT BLUE (-6725 1350);
DISPLAY INVISIBLE (-6725 1350);
FORCEPROP 1 LAST MATERIAL CHIP
J 0
(-6500 1200);
DISPLAY 0.617021 (-6500 1200);
PAINT SKYBLUE (-6500 1200);
DISPLAY INVISIBLE (-6500 1200);
FORCEPROP 0 LAST ROOM BMC
J 0
(-6525 1475);
DISPLAY 1.021277 (-6525 1475);
PAINT ORANGE (-6525 1475);
DISPLAY INVISIBLE (-6525 1475);
FORCEPROP 0 LAST BOM_COST SB
J 0
(-6525 1575);
DISPLAY 1.021277 (-6525 1575);
PAINT ORANGE (-6525 1575);
DISPLAY INVISIBLE (-6525 1575);
FORCEPROP 2 LAST CDS_LIB mstr_discrete
J 0
(-6500 1350);
PAINT MONO (-6500 1350);
DISPLAY INVISIBLE (-6500 1350);
FORCEPROP 1 LASTPIN (-6600 1350) $PN 1
J 0
(-6588 1362);
DISPLAY 0.787234 (-6588 1362);
PAINT ORANGE (-6588 1362);
DISPLAY INVISIBLE (-6588 1362);
FORCEPROP 1 LASTPIN (-6400 1350) $PN 2
J 0
(-6438 1362);
DISPLAY 0.787234 (-6438 1362);
PAINT ORANGE (-6438 1362);
DISPLAY INVISIBLE (-6438 1362);
FORCEADD RES..1
(-6500 1250);
FORCEPROP 1 LAST VALUE 33.2
J 2
(-6550 1250);
DISPLAY 0.617021 (-6550 1250);
PAINT SKYBLUE (-6550 1250);
FORCEPROP 1 LAST LOCATION R3N26
J 0
(-6775 1250);
DISPLAY 0.617021 (-6775 1250);
PAINT AQUA (-6775 1250);
FORCEPROP 1 LAST PACK_TYPE 0402
J 0
(-6400 1250);
DISPLAY 0.617021 (-6400 1250);
PAINT SKYBLUE (-6400 1250);
FORCEPROP 1 LAST MATERIAL CHIP
J 0
(-6500 1100);
DISPLAY 0.617021 (-6500 1100);
PAINT SKYBLUE (-6500 1100);
DISPLAY INVISIBLE (-6500 1100);
FORCEPROP 0 LAST ROOM BMC
J 0
(-6525 1375);
DISPLAY 1.021277 (-6525 1375);
PAINT ORANGE (-6525 1375);
DISPLAY INVISIBLE (-6525 1375);
FORCEPROP 0 LAST BOM_COST SB
J 0
(-6525 1475);
DISPLAY 1.021277 (-6525 1475);
PAINT ORANGE (-6525 1475);
DISPLAY INVISIBLE (-6525 1475);
FORCEPROP 2 LAST CDS_LIB mstr_discrete
J 0
(-6500 1250);
PAINT MONO (-6500 1250);
DISPLAY INVISIBLE (-6500 1250);
FORCEPROP 1 LAST PART_NUMBER G21796-074
J 0
(-6750 1250);
DISPLAY 0.617021 (-6750 1250);
PAINT BLUE (-6750 1250);
DISPLAY INVISIBLE (-6750 1250);
FORCEPROP 1 LAST TOLERANCE 1%
J 0
(-6450 1225);
DISPLAY 0.617021 (-6450 1225);
PAINT SKYBLUE (-6450 1225);
DISPLAY INVISIBLE (-6450 1225);
FORCEPROP 1 LAST WATTAGE 1/16W
J 2
(-6200 1225);
DISPLAY 0.617021 (-6200 1225);
PAINT SKYBLUE (-6200 1225);
DISPLAY INVISIBLE (-6200 1225);
FORCEPROP 1 LAST PATH I75
J 0
(-6550 1400);
DISPLAY 0.978723 (-6550 1400);
PAINT WHITE (-6550 1400);
DISPLAY INVISIBLE (-6550 1400);
FORCEPROP 1 LASTPIN (-6600 1250) $PN 1
J 0
(-6588 1262);
DISPLAY 0.787234 (-6588 1262);
PAINT ORANGE (-6588 1262);
DISPLAY INVISIBLE (-6588 1262);
FORCEPROP 1 LASTPIN (-6400 1250) $PN 2
J 0
(-6438 1262);
DISPLAY 0.787234 (-6438 1262);
PAINT ORANGE (-6438 1262);
DISPLAY INVISIBLE (-6438 1262);
FORCEADD RES..2
(-5800 800);
FORCEPROP 1 LAST TOLERANCE 1%
J 0
(-5755 825);
DISPLAY 0.617021 (-5755 825);
PAINT SKYBLUE (-5755 825);
FORCEPROP 1 LAST PART_NUMBER G21796-010
J 0
(-5760 675);
DISPLAY 0.617021 (-5760 675);
PAINT BLUE (-5760 675);
FORCEPROP 1 LAST WATTAGE 1/16W
J 0
(-5760 775);
DISPLAY 0.617021 (-5760 775);
PAINT SKYBLUE (-5760 775);
FORCEPROP 1 LAST VALUE 100.0K
J 0
(-5755 875);
DISPLAY 0.617021 (-5755 875);
PAINT SKYBLUE (-5755 875);
FORCEPROP 1 LAST MATERIAL CHIP
J 0
(-5760 725);
DISPLAY 0.617021 (-5760 725);
PAINT SKYBLUE (-5760 725);
FORCEPROP 1 LAST PACK_TYPE 0402
J 0
(-5760 625);
DISPLAY 0.617021 (-5760 625);
PAINT SKYBLUE (-5760 625);
FORCEPROP 1 LAST LOCATION R25W66
J 0
(-5755 925);
DISPLAY 0.617021 (-5755 925);
PAINT AQUA (-5755 925);
FORCEPROP 2 LAST CDS_SEC 1
J 0
(-5750 1025);
DISPLAY 1.021277 (-5750 1025);
PAINT ORANGE (-5750 1025);
DISPLAY INVISIBLE (-5750 1025);
FORCEPROP 2 LAST $SEC 1
J 0
(-5750 1025);
DISPLAY 0.680851 (-5750 1025);
PAINT MONO (-5750 1025);
DISPLAY INVISIBLE (-5750 1025);
FORCEPROP 2 LAST ROOM BMC
J 0
(-5750 975);
PAINT MONO (-5750 975);
DISPLAY INVISIBLE (-5750 975);
FORCEPROP 2 LAST CDS_LIB mstr_discrete
J 0
(-5800 800);
PAINT ORANGE (-5800 800);
DISPLAY INVISIBLE (-5800 800);
FORCEPROP 1 LASTPIN (-5800 900) $PN 1
J 0
(-5795 862);
DISPLAY 0.787234 (-5795 862);
PAINT ORANGE (-5795 862);
DISPLAY INVISIBLE (-5795 862);
FORCEPROP 1 LASTPIN (-5800 700) $PN 2
J 0
(-5795 710);
DISPLAY 0.787234 (-5795 710);
PAINT ORANGE (-5795 710);
DISPLAY INVISIBLE (-5795 710);
FORCEPROP 1 LAST PATH I76
J 0
(-5750 975);
DISPLAY 0.978723 (-5750 975);
PAINT WHITE (-5750 975);
DISPLAY INVISIBLE (-5750 975);
FORCEPROP 2 LAST CDS_LOCATION R25W66
J 0
(-5755 925);
DISPLAY 0.617021 (-5755 925);
PAINT AQUA (-5755 925);
DISPLAY INVISIBLE (-5755 925);
FORCEADD GND..1
(-5800 450);
FORCEPROP 3 LASTPIN (-5800 500) SIG_NAME GND\g
J 0
(-5790 510);
DISPLAY 0.659574 (-5790 510);
PAINT MONO (-5790 510);
DISPLAY INVISIBLE (-5790 510);
FORCEPROP 1 LAST HDL_POWER GND
J 0
(-5800 600);
DISPLAY 0.872340 (-5800 600);
PAINT GREEN (-5800 600);
DISPLAY INVISIBLE (-5800 600);
FORCEPROP 1 LAST BODY_TYPE PLUMBING
J 0
(-5845 407);
DISPLAY 0.340426 (-5845 407);
PAINT GREEN (-5845 407);
DISPLAY INVISIBLE (-5845 407);
FORCEPROP 1 LAST VOLTAGE 0.0V
J 0
(-5845 407);
DISPLAY 0.340426 (-5845 407);
PAINT SKYBLUE (-5845 407);
DISPLAY INVISIBLE (-5845 407);
FORCEPROP 2 LAST CDS_LIB mstr_symbols
J 0
(-5800 450);
PAINT ORANGE (-5800 450);
DISPLAY INVISIBLE (-5800 450);
FORCEPROP 1 LAST SIZE 1B
J 0
(-5725 400);
DISPLAY 0.872340 (-5725 400);
PAINT AQUA (-5725 400);
DISPLAY INVISIBLE (-5725 400);
FORCEPROP 1 LAST PATH I77
J 0
(-5725 450);
DISPLAY 0.872340 (-5725 450);
PAINT AQUA (-5725 450);
DISPLAY INVISIBLE (-5725 450);
FORCEADD RES..1
(-6725 2650);
FORCEPROP 1 LASTPIN (-6625 2650) $PN 2
J 0
(-6663 2662);
DISPLAY 0.617021 (-6663 2662);
PAINT ORANGE (-6663 2662);
FORCEPROP 1 LAST PACK_TYPE 0402
J 0
(-6475 2600);
DISPLAY 0.617021 (-6475 2600);
PAINT SKYBLUE (-6475 2600);
FORCEPROP 1 LAST TOLERANCE 1%
J 0
(-6675 2600);
DISPLAY 0.617021 (-6675 2600);
PAINT SKYBLUE (-6675 2600);
FORCEPROP 1 LAST LOCATION R1U7
J 0
(-6775 2700);
DISPLAY 0.617021 (-6775 2700);
PAINT AQUA (-6775 2700);
FORCEPROP 1 LASTPIN (-6825 2650) $PN 1
J 0
(-6813 2662);
DISPLAY 0.617021 (-6813 2662);
PAINT ORANGE (-6813 2662);
FORCEPROP 1 LAST VALUE 10.0K
J 2
(-6700 2600);
DISPLAY 0.617021 (-6700 2600);
PAINT SKYBLUE (-6700 2600);
FORCEPROP 1 LAST WATTAGE 1/16W
J 2
(-6825 2600);
DISPLAY 0.617021 (-6825 2600);
PAINT SKYBLUE (-6825 2600);
FORCEPROP 1 LAST PART_NUMBER G21796-016
J 0
(-6775 2750);
DISPLAY 0.617021 (-6775 2750);
PAINT BLUE (-6775 2750);
FORCEPROP 1 LAST MATERIAL CHIP
J 0
(-6600 2600);
DISPLAY 0.617021 (-6600 2600);
PAINT SKYBLUE (-6600 2600);
FORCEPROP 1 LAST PATH I78
J 0
(-6775 2800);
DISPLAY 0.978723 (-6775 2800);
PAINT WHITE (-6775 2800);
DISPLAY INVISIBLE (-6775 2800);
FORCEPROP 2 LAST CDS_LOCATION R1U7
J 0
(-6775 2700);
DISPLAY 0.617021 (-6775 2700);
PAINT AQUA (-6775 2700);
DISPLAY INVISIBLE (-6775 2700);
FORCEPROP 2 LAST CDS_LIB mstr_discrete
J 0
(-6725 2650);
PAINT ORANGE (-6725 2650);
DISPLAY INVISIBLE (-6725 2650);
FORCEPROP 0 LAST BOM_COST SM_CONTROLLER
J 0
(-6675 2975);
DISPLAY 1.021277 (-6675 2975);
PAINT ORANGE (-6675 2975);
DISPLAY INVISIBLE (-6675 2975);
FORCEPROP 0 LAST ROOM BMC
J 0
(-6675 2875);
DISPLAY 1.021277 (-6675 2875);
PAINT ORANGE (-6675 2875);
DISPLAY INVISIBLE (-6675 2875);
FORCEPROP 2 LAST SEC_TYPE 0402
J 0
(-6775 2850);
DISPLAY 1.021277 (-6775 2850);
PAINT ORANGE (-6775 2850);
DISPLAY INVISIBLE (-6775 2850);
FORCEPROP 2 LAST SEC 1
J 0
(-6775 2850);
DISPLAY 0.680851 (-6775 2850);
PAINT MONO (-6775 2850);
DISPLAY INVISIBLE (-6775 2850);
FORCEPROP 0 LAST CDS_SEC 1
J 0
(-6775 2800);
PAINT MONO (-6775 2800);
DISPLAY INVISIBLE (-6775 2800);
FORCEADD GND..1
R 5
(-7050 2650);
FORCEPROP 3 LASTPIN (-7000 2650) SIG_NAME GND\g
J 0
(-6990 2660);
DISPLAY 0.659574 (-6990 2660);
PAINT MONO (-6990 2660);
DISPLAY INVISIBLE (-6990 2660);
FORCEPROP 1 LAST HDL_POWER GND
R 3
J 0
(-6900 2650);
DISPLAY 0.872340 (-6900 2650);
PAINT GREEN (-6900 2650);
DISPLAY INVISIBLE (-6900 2650);
FORCEPROP 1 LAST BODY_TYPE PLUMBING
R 3
J 0
(-7093 2695);
DISPLAY 0.340426 (-7093 2695);
PAINT GREEN (-7093 2695);
DISPLAY INVISIBLE (-7093 2695);
FORCEPROP 1 LAST PATH I79
R 3
J 0
(-7050 2575);
DISPLAY 0.872340 (-7050 2575);
PAINT AQUA (-7050 2575);
DISPLAY INVISIBLE (-7050 2575);
FORCEPROP 1 LAST VOLTAGE 0.0V
R 3
J 0
(-7093 2695);
DISPLAY 0.340426 (-7093 2695);
PAINT SKYBLUE (-7093 2695);
DISPLAY INVISIBLE (-7093 2695);
FORCEPROP 1 LAST SIZE 1B
R 3
J 0
(-7100 2575);
DISPLAY 0.872340 (-7100 2575);
PAINT AQUA (-7100 2575);
DISPLAY INVISIBLE (-7100 2575);
FORCEPROP 2 LAST CDS_LIB mstr_symbols
R 3
J 0
(-7050 2650);
PAINT ORANGE (-7050 2650);
DISPLAY INVISIBLE (-7050 2650);
FORCEADD OFFPAGE..1
(-7150 2450);
FORCEPROP 2 LAST $XR2 151 
J 0
(-7672 2450);
DISPLAY 0.638298 (-7672 2450);
PAINT MONO (-7672 2450);
FORCEPROP 2 LAST $XR1 246 
J 0
(-7552 2450);
DISPLAY 0.638298 (-7552 2450);
PAINT MONO (-7552 2450);
FORCEPROP 2 LAST $XR0 162 
J 0
(-7432 2450);
DISPLAY 0.638298 (-7432 2450);
PAINT MONO (-7432 2450);
FORCEPROP 1 LAST COMMENT_BODY TRUE
J 0
(-7025 2350);
DISPLAY 0.872340 (-7025 2350);
PAINT GREEN (-7025 2350);
DISPLAY INVISIBLE (-7025 2350);
FORCEPROP 1 LAST OFFPAGE TRUE
J 0
(-6825 2325);
DISPLAY 0.872340 (-6825 2325);
PAINT GREEN (-6825 2325);
DISPLAY INVISIBLE (-6825 2325);
FORCEPROP 2 LAST BOM_COST SM_CONTROLLER
J 0
(-6700 2500);
PAINT MONO (-6700 2500);
DISPLAY INVISIBLE (-6700 2500);
FORCEPROP 2 LAST ROOM BMC
J 0
(-7400 2525);
DISPLAY 1.361702 (-7400 2525);
PAINT ORANGE (-7400 2525);
DISPLAY INVISIBLE (-7400 2525);
FORCEPROP 2 LAST CDS_LIB mstr_standard
J 0
(-7150 2450);
PAINT MONO (-7150 2450);
DISPLAY INVISIBLE (-7150 2450);
FORCEPROP 2 LAST PATH I80
J 0
(-7100 2525);
DISPLAY 1.021277 (-7100 2525);
PAINT ORANGE (-7100 2525);
DISPLAY INVISIBLE (-7100 2525);
FORCEADD OFFPAGE..5
(-7175 2500);
FORCEPROP 2 LAST $XR2 246 
J 0
(-7700 2500);
DISPLAY 0.638298 (-7700 2500);
PAINT MONO (-7700 2500);
FORCEPROP 2 LAST $XR1 162 
J 0
(-7580 2500);
DISPLAY 0.638298 (-7580 2500);
PAINT MONO (-7580 2500);
FORCEPROP 2 LAST $XR0 151 
J 0
(-7460 2500);
DISPLAY 0.638298 (-7460 2500);
PAINT MONO (-7460 2500);
FORCEPROP 1 LAST COMMENT_BODY TRUE
J 0
(-7075 2425);
DISPLAY 0.872340 (-7075 2425);
PAINT GREEN (-7075 2425);
DISPLAY INVISIBLE (-7075 2425);
FORCEPROP 1 LAST OFFPAGE TRUE
J 0
(-6850 2375);
DISPLAY 0.872340 (-6850 2375);
PAINT GREEN (-6850 2375);
DISPLAY INVISIBLE (-6850 2375);
FORCEPROP 2 LAST CDS_LIB mstr_standard
J 0
(-7175 2500);
PAINT MONO (-7175 2500);
DISPLAY INVISIBLE (-7175 2500);
FORCEPROP 2 LAST PATH I81
J 0
(-7125 2575);
DISPLAY 1.021277 (-7125 2575);
PAINT ORANGE (-7125 2575);
DISPLAY INVISIBLE (-7125 2575);
FORCEADD OFFPAGE..5
(-7175 2400);
FORCEPROP 2 LAST $XR1 162 
J 0
(-7460 2400);
DISPLAY 0.638298 (-7460 2400);
PAINT MONO (-7460 2400);
FORCEPROP 2 LAST $XR2 ?
J 0
(-7660 2400);
DISPLAY 0.638298 (-7660 2400);
PAINT MONO (-7660 2400);
FORCEPROP 2 LAST $XR0 151 
J 0
(-7560 2400);
DISPLAY 0.638298 (-7560 2400);
PAINT MONO (-7560 2400);
FORCEPROP 1 LAST COMMENT_BODY TRUE
J 0
(-7075 2325);
DISPLAY 0.872340 (-7075 2325);
PAINT GREEN (-7075 2325);
DISPLAY INVISIBLE (-7075 2325);
FORCEPROP 1 LAST OFFPAGE TRUE
J 0
(-6850 2275);
DISPLAY 0.872340 (-6850 2275);
PAINT GREEN (-6850 2275);
DISPLAY INVISIBLE (-6850 2275);
FORCEPROP 2 LAST CDS_LIB mstr_standard
J 0
(-7175 2400);
PAINT ORANGE (-7175 2400);
DISPLAY INVISIBLE (-7175 2400);
FORCEPROP 2 LAST PATH I82
J 0
(-7450 2450);
DISPLAY 1.021277 (-7450 2450);
PAINT ORANGE (-7450 2450);
DISPLAY INVISIBLE (-7450 2450);
FORCEADD OFFPAGE..5
(-7175 2350);
FORCEPROP 2 LAST $XR2 246 
J 0
(-7700 2350);
DISPLAY 0.638298 (-7700 2350);
PAINT MONO (-7700 2350);
FORCEPROP 2 LAST $XR1 162 
J 0
(-7580 2350);
DISPLAY 0.638298 (-7580 2350);
PAINT MONO (-7580 2350);
FORCEPROP 2 LAST $XR0 151 
J 0
(-7460 2350);
DISPLAY 0.638298 (-7460 2350);
PAINT MONO (-7460 2350);
FORCEPROP 1 LAST COMMENT_BODY TRUE
J 0
(-7075 2275);
DISPLAY 0.872340 (-7075 2275);
PAINT GREEN (-7075 2275);
DISPLAY INVISIBLE (-7075 2275);
FORCEPROP 1 LAST OFFPAGE TRUE
J 0
(-6850 2225);
DISPLAY 0.872340 (-6850 2225);
PAINT GREEN (-6850 2225);
DISPLAY INVISIBLE (-6850 2225);
FORCEPROP 2 LAST CDS_LIB mstr_standard
J 0
(-7175 2350);
PAINT MONO (-7175 2350);
DISPLAY INVISIBLE (-7175 2350);
FORCEPROP 2 LAST PATH I83
J 0
(-7125 2425);
DISPLAY 1.021277 (-7125 2425);
PAINT ORANGE (-7125 2425);
DISPLAY INVISIBLE (-7125 2425);
FORCEADD RES..1
(-6850 1400);
FORCEPROP 1 LAST VALUE 33.2
J 2
(-6675 1400);
DISPLAY 0.617021 (-6675 1400);
PAINT SKYBLUE (-6675 1400);
FORCEPROP 1 LAST LOCATION R25W68
J 0
(-7075 1400);
DISPLAY 0.617021 (-7075 1400);
PAINT AQUA (-7075 1400);
FORCEPROP 1 LAST PACK_TYPE 0402
J 0
(-6650 1400);
DISPLAY 0.617021 (-6650 1400);
PAINT SKYBLUE (-6650 1400);
FORCEPROP 1 LAST PATH I84
J 0
(-6900 1550);
DISPLAY 0.978723 (-6900 1550);
PAINT WHITE (-6900 1550);
DISPLAY INVISIBLE (-6900 1550);
FORCEPROP 1 LAST PART_NUMBER G21796-074
J 0
(-7125 1400);
DISPLAY 0.617021 (-7125 1400);
PAINT BLUE (-7125 1400);
DISPLAY INVISIBLE (-7125 1400);
FORCEPROP 1 LAST MATERIAL CHIP
J 0
(-6850 1250);
DISPLAY 0.617021 (-6850 1250);
PAINT SKYBLUE (-6850 1250);
DISPLAY INVISIBLE (-6850 1250);
FORCEPROP 0 LAST ROOM BMC
J 0
(-6875 1525);
DISPLAY 1.021277 (-6875 1525);
PAINT ORANGE (-6875 1525);
DISPLAY INVISIBLE (-6875 1525);
FORCEPROP 0 LAST BOM_COST SB
J 0
(-6875 1625);
DISPLAY 1.021277 (-6875 1625);
PAINT ORANGE (-6875 1625);
DISPLAY INVISIBLE (-6875 1625);
FORCEPROP 2 LAST CDS_LIB mstr_discrete
J 0
(-6850 1400);
PAINT MONO (-6850 1400);
DISPLAY INVISIBLE (-6850 1400);
FORCEPROP 1 LAST WATTAGE 1/16W
J 2
(-6975 1375);
DISPLAY 0.617021 (-6975 1375);
PAINT SKYBLUE (-6975 1375);
DISPLAY INVISIBLE (-6975 1375);
FORCEPROP 1 LAST TOLERANCE 1%
J 0
(-6800 1375);
DISPLAY 0.617021 (-6800 1375);
PAINT SKYBLUE (-6800 1375);
DISPLAY INVISIBLE (-6800 1375);
FORCEPROP 1 LASTPIN (-6950 1400) $PN 1
J 0
(-6938 1412);
DISPLAY 0.787234 (-6938 1412);
PAINT ORANGE (-6938 1412);
DISPLAY INVISIBLE (-6938 1412);
FORCEPROP 1 LASTPIN (-6750 1400) $PN 2
J 0
(-6788 1412);
DISPLAY 0.787234 (-6788 1412);
PAINT ORANGE (-6788 1412);
DISPLAY INVISIBLE (-6788 1412);
FORCEADD RES..1
(-6850 1300);
FORCEPROP 1 LAST VALUE 33.2
J 2
(-6700 1300);
DISPLAY 0.617021 (-6700 1300);
PAINT SKYBLUE (-6700 1300);
FORCEPROP 1 LAST LOCATION R25W69
J 0
(-7075 1300);
DISPLAY 0.617021 (-7075 1300);
PAINT AQUA (-7075 1300);
FORCEPROP 1 LAST PACK_TYPE 0402
J 0
(-6675 1300);
DISPLAY 0.617021 (-6675 1300);
PAINT SKYBLUE (-6675 1300);
FORCEPROP 1 LAST PATH I85
J 0
(-6900 1450);
DISPLAY 0.978723 (-6900 1450);
PAINT WHITE (-6900 1450);
DISPLAY INVISIBLE (-6900 1450);
FORCEPROP 2 LAST CDS_LIB mstr_discrete
J 0
(-6850 1300);
PAINT MONO (-6850 1300);
DISPLAY INVISIBLE (-6850 1300);
FORCEPROP 0 LAST BOM_COST SB
J 0
(-6875 1525);
DISPLAY 1.021277 (-6875 1525);
PAINT ORANGE (-6875 1525);
DISPLAY INVISIBLE (-6875 1525);
FORCEPROP 0 LAST ROOM BMC
J 0
(-6875 1425);
DISPLAY 1.021277 (-6875 1425);
PAINT ORANGE (-6875 1425);
DISPLAY INVISIBLE (-6875 1425);
FORCEPROP 1 LAST MATERIAL CHIP
J 0
(-6850 1150);
DISPLAY 0.617021 (-6850 1150);
PAINT SKYBLUE (-6850 1150);
DISPLAY INVISIBLE (-6850 1150);
FORCEPROP 1 LAST PART_NUMBER G21796-074
J 0
(-7125 1300);
DISPLAY 0.617021 (-7125 1300);
PAINT BLUE (-7125 1300);
DISPLAY INVISIBLE (-7125 1300);
FORCEPROP 1 LAST TOLERANCE 1%
J 0
(-6800 1275);
DISPLAY 0.617021 (-6800 1275);
PAINT SKYBLUE (-6800 1275);
DISPLAY INVISIBLE (-6800 1275);
FORCEPROP 1 LAST WATTAGE 1/16W
J 2
(-6575 1275);
DISPLAY 0.617021 (-6575 1275);
PAINT SKYBLUE (-6575 1275);
DISPLAY INVISIBLE (-6575 1275);
FORCEPROP 1 LASTPIN (-6950 1300) $PN 1
J 0
(-6938 1312);
DISPLAY 0.787234 (-6938 1312);
PAINT ORANGE (-6938 1312);
DISPLAY INVISIBLE (-6938 1312);
FORCEPROP 1 LASTPIN (-6750 1300) $PN 2
J 0
(-6788 1312);
DISPLAY 0.787234 (-6788 1312);
PAINT ORANGE (-6788 1312);
DISPLAY INVISIBLE (-6788 1312);
FORCEADD OFFPAGE..1
(-7125 1750);
FORCEPROP 2 LAST $XR0 191 
J 0
(-7582 1750);
DISPLAY 0.638298 (-7582 1750);
PAINT MONO (-7582 1750);
FORCEPROP 2 LAST $XR3 184 
J 0
(-7682 1750);
DISPLAY 0.638298 (-7682 1750);
PAINT MONO (-7682 1750);
FORCEPROP 2 LAST $XR1 134 
J 0
(-7507 1750);
DISPLAY 0.638298 (-7507 1750);
PAINT MONO (-7507 1750);
FORCEPROP 2 LAST $XR2 145 
J 0
(-7407 1750);
DISPLAY 0.638298 (-7407 1750);
PAINT MONO (-7407 1750);
FORCEPROP 1 LAST COMMENT_BODY TRUE
J 0
(-7000 1650);
DISPLAY 0.872340 (-7000 1650);
PAINT GREEN (-7000 1650);
DISPLAY INVISIBLE (-7000 1650);
FORCEPROP 1 LAST OFFPAGE TRUE
J 0
(-6800 1625);
DISPLAY 0.872340 (-6800 1625);
PAINT GREEN (-6800 1625);
DISPLAY INVISIBLE (-6800 1625);
FORCEPROP 2 LAST PATH I86
J 0
(-7400 1800);
DISPLAY 1.021277 (-7400 1800);
PAINT ORANGE (-7400 1800);
DISPLAY INVISIBLE (-7400 1800);
FORCEPROP 2 LAST BOM_COST SM_CONTROLLER
J 0
(-6675 1800);
PAINT MONO (-6675 1800);
DISPLAY INVISIBLE (-6675 1800);
FORCEPROP 2 LAST CDS_LIB mstr_standard
J 2
(-7125 1750);
PAINT ORANGE (-7125 1750);
DISPLAY INVISIBLE (-7125 1750);
FORCEPROP 2 LAST ROOM BMC
J 0
(-7375 1825);
DISPLAY 1.361702 (-7375 1825);
PAINT ORANGE (-7375 1825);
DISPLAY INVISIBLE (-7375 1825);
FORCEADD OFFPAGE..3
R 2
(-7125 1675);
FORCEPROP 2 LAST $XR1 119 
J 0
(-7405 1675);
DISPLAY 0.638298 (-7405 1675);
PAINT MONO (-7405 1675);
FORCEPROP 2 LAST $XR0 133 
J 0
(-7505 1675);
DISPLAY 0.638298 (-7505 1675);
PAINT MONO (-7505 1675);
FORCEPROP 1 LAST COMMENT_BODY TRUE
J 2
(-7075 1575);
DISPLAY 1.170213 (-7075 1575);
PAINT GREEN (-7075 1575);
DISPLAY INVISIBLE (-7075 1575);
FORCEPROP 1 LAST OFFPAGE TRUE
J 2
(-7450 1550);
PAINT GREEN (-7450 1550);
DISPLAY INVISIBLE (-7450 1550);
FORCEPROP 2 LAST PATH I87
J 0
(-7400 1725);
DISPLAY 1.021277 (-7400 1725);
PAINT ORANGE (-7400 1725);
DISPLAY INVISIBLE (-7400 1725);
FORCEPROP 2 LAST CDS_LIB mstr_standard
J 0
(-7125 1675);
PAINT ORANGE (-7125 1675);
DISPLAY INVISIBLE (-7125 1675);
FORCEPROP 2 LAST ROOM BMC
J 2
(-7600 1725);
PAINT MONO (-7600 1725);
DISPLAY INVISIBLE (-7600 1725);
FORCEPROP 2 LAST BOM_COST SM_CONTROLLER
J 2
(-7600 1725);
PAINT MONO (-7600 1725);
DISPLAY INVISIBLE (-7600 1725);
FORCEADD OFFPAGE..3
R 2
(-7125 1600);
FORCEPROP 2 LAST $XR0 119 
J 0
(-7405 1600);
DISPLAY 0.638298 (-7405 1600);
PAINT MONO (-7405 1600);
FORCEPROP 1 LAST COMMENT_BODY TRUE
J 2
(-7075 1500);
DISPLAY 1.170213 (-7075 1500);
PAINT GREEN (-7075 1500);
DISPLAY INVISIBLE (-7075 1500);
FORCEPROP 1 LAST OFFPAGE TRUE
J 2
(-7450 1475);
PAINT GREEN (-7450 1475);
DISPLAY INVISIBLE (-7450 1475);
FORCEPROP 2 LAST PATH I88
J 0
(-7400 1650);
DISPLAY 1.021277 (-7400 1650);
PAINT ORANGE (-7400 1650);
DISPLAY INVISIBLE (-7400 1650);
FORCEPROP 2 LAST BOM_COST SM_CONTROLLER
J 2
(-7600 1650);
PAINT MONO (-7600 1650);
DISPLAY INVISIBLE (-7600 1650);
FORCEPROP 2 LAST ROOM BMC
J 2
(-7600 1650);
PAINT MONO (-7600 1650);
DISPLAY INVISIBLE (-7600 1650);
FORCEPROP 2 LAST CDS_LIB mstr_standard
J 0
(-7125 1600);
PAINT ORANGE (-7125 1600);
DISPLAY INVISIBLE (-7125 1600);
FORCEADD OFFPAGE..1
(-7150 1500);
FORCEPROP 2 LAST $XR1 ?
J 0
(-7432 1500);
DISPLAY 0.638298 (-7432 1500);
PAINT MONO (-7432 1500);
FORCEPROP 2 LAST $XR0 119 
J 0
(-7432 1500);
DISPLAY 0.638298 (-7432 1500);
PAINT MONO (-7432 1500);
FORCEPROP 1 LAST COMMENT_BODY TRUE
J 0
(-7025 1400);
DISPLAY 0.872340 (-7025 1400);
PAINT GREEN (-7025 1400);
DISPLAY INVISIBLE (-7025 1400);
FORCEPROP 1 LAST OFFPAGE TRUE
J 0
(-6825 1375);
DISPLAY 0.872340 (-6825 1375);
PAINT GREEN (-6825 1375);
DISPLAY INVISIBLE (-6825 1375);
FORCEPROP 2 LAST PATH I89
J 0
(-7425 1550);
DISPLAY 1.021277 (-7425 1550);
PAINT ORANGE (-7425 1550);
DISPLAY INVISIBLE (-7425 1550);
FORCEPROP 2 LAST BOM_COST SM_CONTROLLER
J 0
(-6700 1550);
PAINT MONO (-6700 1550);
DISPLAY INVISIBLE (-6700 1550);
FORCEPROP 2 LAST CDS_LIB mstr_standard
J 2
(-7150 1500);
PAINT ORANGE (-7150 1500);
DISPLAY INVISIBLE (-7150 1500);
FORCEPROP 2 LAST ROOM BMC
J 0
(-7400 1575);
DISPLAY 1.361702 (-7400 1575);
PAINT ORANGE (-7400 1575);
DISPLAY INVISIBLE (-7400 1575);
FORCEADD TAP..1
R 2
(-7250 1400);
FORCEPROP 3 LASTPIN (-7200 1400) SIG_NAME LPC_LAD_IO<3>
J 0
(-7190 1410);
DISPLAY 0.659574 (-7190 1410);
PAINT MONO (-7190 1410);
DISPLAY INVISIBLE (-7190 1410);
FORCEPROP 1 LASTPIN (-7200 1400) BN 3
J 2
(-7188 1408);
DISPLAY 0.680851 (-7188 1408);
PAINT GREEN (-7188 1408);
FORCEPROP 1 LAST HDL_TAP TRUE
J 2
(-7575 1275);
DISPLAY 0.872340 (-7575 1275);
PAINT ORANGE (-7575 1275);
DISPLAY INVISIBLE (-7575 1275);
FORCEPROP 1 LAST BODY_TYPE PLUMBING
J 2
(-7250 1450);
DISPLAY 0.872340 (-7250 1450);
PAINT GREEN (-7250 1450);
DISPLAY INVISIBLE (-7250 1450);
FORCEPROP 1 LAST PATH I90
J 2
(-7248 1400);
DISPLAY 0.872340 (-7248 1400);
PAINT GREEN (-7248 1400);
DISPLAY INVISIBLE (-7248 1400);
FORCEPROP 2 LAST CDS_LIB mstr_standard
J 0
(-7250 1400);
PAINT MONO (-7250 1400);
DISPLAY INVISIBLE (-7250 1400);
FORCEADD TAP..1
R 2
(-7250 1250);
FORCEPROP 3 LASTPIN (-7200 1250) SIG_NAME LPC_LAD_IO<0>
J 0
(-7190 1260);
DISPLAY 0.659574 (-7190 1260);
PAINT MONO (-7190 1260);
DISPLAY INVISIBLE (-7190 1260);
FORCEPROP 1 LASTPIN (-7200 1250) BN 0
J 2
(-7188 1258);
DISPLAY 0.680851 (-7188 1258);
PAINT GREEN (-7188 1258);
FORCEPROP 1 LAST HDL_TAP TRUE
J 2
(-7575 1125);
DISPLAY 0.872340 (-7575 1125);
PAINT ORANGE (-7575 1125);
DISPLAY INVISIBLE (-7575 1125);
FORCEPROP 1 LAST BODY_TYPE PLUMBING
J 2
(-7250 1300);
DISPLAY 0.872340 (-7250 1300);
PAINT GREEN (-7250 1300);
DISPLAY INVISIBLE (-7250 1300);
FORCEPROP 1 LAST PATH I91
J 2
(-7248 1250);
DISPLAY 0.872340 (-7248 1250);
PAINT GREEN (-7248 1250);
DISPLAY INVISIBLE (-7248 1250);
FORCEPROP 2 LAST CDS_LIB mstr_standard
J 0
(-7250 1250);
PAINT MONO (-7250 1250);
DISPLAY INVISIBLE (-7250 1250);
FORCEADD TAP..1
R 2
(-7250 1300);
FORCEPROP 3 LASTPIN (-7200 1300) SIG_NAME LPC_LAD_IO<1>
J 0
(-7190 1310);
DISPLAY 0.659574 (-7190 1310);
PAINT MONO (-7190 1310);
DISPLAY INVISIBLE (-7190 1310);
FORCEPROP 1 LASTPIN (-7200 1300) BN 1
J 2
(-7188 1308);
DISPLAY 0.680851 (-7188 1308);
PAINT GREEN (-7188 1308);
FORCEPROP 1 LAST HDL_TAP TRUE
J 2
(-7575 1175);
DISPLAY 0.872340 (-7575 1175);
PAINT ORANGE (-7575 1175);
DISPLAY INVISIBLE (-7575 1175);
FORCEPROP 1 LAST BODY_TYPE PLUMBING
J 2
(-7250 1350);
DISPLAY 0.872340 (-7250 1350);
PAINT GREEN (-7250 1350);
DISPLAY INVISIBLE (-7250 1350);
FORCEPROP 1 LAST PATH I92
J 2
(-7248 1300);
DISPLAY 0.872340 (-7248 1300);
PAINT GREEN (-7248 1300);
DISPLAY INVISIBLE (-7248 1300);
FORCEPROP 2 LAST CDS_LIB mstr_standard
J 0
(-7250 1300);
PAINT MONO (-7250 1300);
DISPLAY INVISIBLE (-7250 1300);
FORCEADD TAP..1
R 2
(-7250 1350);
FORCEPROP 3 LASTPIN (-7200 1350) SIG_NAME LPC_LAD_IO<2>
J 0
(-7190 1360);
DISPLAY 0.659574 (-7190 1360);
PAINT MONO (-7190 1360);
DISPLAY INVISIBLE (-7190 1360);
FORCEPROP 1 LASTPIN (-7200 1350) BN 2
J 2
(-7188 1358);
DISPLAY 0.680851 (-7188 1358);
PAINT GREEN (-7188 1358);
FORCEPROP 1 LAST HDL_TAP TRUE
J 2
(-7575 1225);
DISPLAY 0.872340 (-7575 1225);
PAINT ORANGE (-7575 1225);
DISPLAY INVISIBLE (-7575 1225);
FORCEPROP 1 LAST BODY_TYPE PLUMBING
J 2
(-7250 1400);
DISPLAY 0.872340 (-7250 1400);
PAINT GREEN (-7250 1400);
DISPLAY INVISIBLE (-7250 1400);
FORCEPROP 1 LAST PATH I93
J 2
(-7248 1350);
DISPLAY 0.872340 (-7248 1350);
PAINT GREEN (-7248 1350);
DISPLAY INVISIBLE (-7248 1350);
FORCEPROP 2 LAST CDS_LIB mstr_standard
J 0
(-7250 1350);
PAINT MONO (-7250 1350);
DISPLAY INVISIBLE (-7250 1350);
FORCEADD OFFPAGE..3
R 2
(-7650 1425);
FORCEPROP 2 LAST $XR0 119 
J 0
(-7930 1425);
DISPLAY 0.638298 (-7930 1425);
PAINT MONO (-7930 1425);
FORCEPROP 1 LAST COMMENT_BODY TRUE
J 2
(-7600 1325);
DISPLAY 1.170213 (-7600 1325);
PAINT GREEN (-7600 1325);
DISPLAY INVISIBLE (-7600 1325);
FORCEPROP 1 LAST OFFPAGE TRUE
J 2
(-7975 1300);
PAINT GREEN (-7975 1300);
DISPLAY INVISIBLE (-7975 1300);
FORCEPROP 2 LAST PATH I94
J 0
(-7600 1500);
DISPLAY 1.021277 (-7600 1500);
PAINT ORANGE (-7600 1500);
DISPLAY INVISIBLE (-7600 1500);
FORCEPROP 2 LAST CDS_LIB mstr_standard
J 0
(-7650 1425);
PAINT MONO (-7650 1425);
DISPLAY INVISIBLE (-7650 1425);
FORCEPROP 2 LAST BOM_COST SM_CONTROLLER
J 2
(-8125 1475);
PAINT MONO (-8125 1475);
DISPLAY INVISIBLE (-8125 1475);
FORCEPROP 2 LAST ROOM BMC
J 2
(-8125 1475);
PAINT MONO (-8125 1475);
DISPLAY INVISIBLE (-8125 1475);
FORCEADD OFFPAGE..1
(-6400 3500);
FORCEPROP 2 LAST $XR0 157 
J 0
(-6832 3500);
DISPLAY 0.638298 (-6832 3500);
PAINT MONO (-6832 3500);
FORCEPROP 2 LAST $XR1 186 
J 0
(-6952 3500);
DISPLAY 0.638298 (-6952 3500);
PAINT MONO (-6952 3500);
FORCEPROP 2 LAST $XR2 119 
J 0
(-7072 3500);
DISPLAY 0.638298 (-7072 3500);
PAINT MONO (-7072 3500);
FORCEPROP 2 LAST CDS_LIB mstr_standard
J 0
(-6400 3500);
PAINT MONO (-6400 3500);
DISPLAY INVISIBLE (-6400 3500);
FORCEPROP 2 LAST PATH I95
J 0
(-6350 3575);
DISPLAY 1.021277 (-6350 3575);
PAINT ORANGE (-6350 3575);
DISPLAY INVISIBLE (-6350 3575);
FORCEPROP 2 LAST BOM_COST SM_CONTROLLER
J 0
(-5950 3550);
PAINT MONO (-5950 3550);
DISPLAY INVISIBLE (-5950 3550);
FORCEPROP 2 LAST ROOM BMC
J 0
(-6650 3575);
DISPLAY 1.361702 (-6650 3575);
PAINT ORANGE (-6650 3575);
DISPLAY INVISIBLE (-6650 3575);
FORCEPROP 1 LAST OFFPAGE TRUE
J 0
(-6075 3375);
DISPLAY 0.872340 (-6075 3375);
PAINT GREEN (-6075 3375);
DISPLAY INVISIBLE (-6075 3375);
FORCEPROP 1 LAST COMMENT_BODY TRUE
J 0
(-6275 3400);
DISPLAY 0.872340 (-6275 3400);
PAINT GREEN (-6275 3400);
DISPLAY INVISIBLE (-6275 3400);
FORCEADD RES..1
(-6625 3950);
FORCEPROP 1 LASTPIN (-6725 3950) $PN 1
J 0
(-6713 3962);
DISPLAY 0.617021 (-6713 3962);
PAINT ORANGE (-6713 3962);
FORCEPROP 1 LASTPIN (-6525 3950) $PN 2
J 0
(-6563 3962);
DISPLAY 0.617021 (-6563 3962);
PAINT ORANGE (-6563 3962);
FORCEPROP 1 LAST TOLERANCE 1.0%
J 0
(-6575 4000);
DISPLAY 0.617021 (-6575 4000);
PAINT SKYBLUE (-6575 4000);
FORCEPROP 1 LAST WATTAGE 1/16W
J 2
(-6725 4000);
DISPLAY 0.617021 (-6725 4000);
PAINT SKYBLUE (-6725 4000);
FORCEPROP 1 LAST LOCATION R2T41
J 0
(-6725 4075);
DISPLAY 0.617021 (-6725 4075);
PAINT AQUA (-6725 4075);
FORCEPROP 1 LAST VALUE 22.1
J 2
(-6600 3975);
DISPLAY 0.617021 (-6600 3975);
PAINT SKYBLUE (-6600 3975);
FORCEPROP 1 LAST PART_NUMBER G21796-250
J 0
(-6825 4025);
DISPLAY 0.617021 (-6825 4025);
PAINT BLUE (-6825 4025);
FORCEPROP 1 LAST PACK_TYPE 0402
J 0
(-6500 3975);
DISPLAY 0.617021 (-6500 3975);
PAINT SKYBLUE (-6500 3975);
FORCEPROP 1 LAST MATERIAL CHIP
J 0
(-6475 4000);
DISPLAY 0.617021 (-6475 4000);
PAINT SKYBLUE (-6475 4000);
FORCEPROP 0 LAST CDS_SEC 1
J 0
(-6675 4025);
PAINT MONO (-6675 4025);
DISPLAY INVISIBLE (-6675 4025);
FORCEPROP 2 LAST SEC 1
J 0
(-6675 4150);
PAINT MONO (-6675 4150);
DISPLAY INVISIBLE (-6675 4150);
FORCEPROP 2 LAST SEC_TYPE 0402
J 0
(-6675 4150);
DISPLAY 1.021277 (-6675 4150);
PAINT ORANGE (-6675 4150);
DISPLAY INVISIBLE (-6675 4150);
FORCEPROP 0 LAST BOM_COST SM_CONTROLLER
J 0
(-6675 4200);
DISPLAY 1.021277 (-6675 4200);
PAINT ORANGE (-6675 4200);
DISPLAY INVISIBLE (-6675 4200);
FORCEPROP 0 LAST ROOM BMC
J 0
(-6675 4100);
DISPLAY 0.617021 (-6675 4100);
PAINT ORANGE (-6675 4100);
DISPLAY INVISIBLE (-6675 4100);
FORCEPROP 2 LAST CDS_LIB mstr_discrete
J 0
(-6625 3950);
PAINT ORANGE (-6625 3950);
DISPLAY INVISIBLE (-6625 3950);
FORCEPROP 2 LAST CDS_LOCATION R2T41
J 0
(-6675 3975);
DISPLAY 0.617021 (-6675 3975);
PAINT AQUA (-6675 3975);
DISPLAY INVISIBLE (-6675 3975);
FORCEPROP 1 LAST PATH I96
J 0
(-6675 4100);
DISPLAY 0.978723 (-6675 4100);
PAINT WHITE (-6675 4100);
DISPLAY INVISIBLE (-6675 4100);
FORCEADD OFFPAGE..5
(-7550 4000);
FORCEPROP 2 LAST $XR0 119 
J 0
(-7805 4000);
DISPLAY 0.638298 (-7805 4000);
PAINT MONO (-7805 4000);
FORCEPROP 2 LAST $XR2 170 
J 0
(-8045 4000);
DISPLAY 0.638298 (-8045 4000);
PAINT MONO (-8045 4000);
FORCEPROP 2 LAST $XR1 120 
J 0
(-7925 4000);
DISPLAY 0.638298 (-7925 4000);
PAINT MONO (-7925 4000);
FORCEPROP 2 LAST $XR3 ?
J 0
(-8045 4000);
DISPLAY 0.638298 (-8045 4000);
PAINT MONO (-8045 4000);
FORCEPROP 1 LAST COMMENT_BODY TRUE
J 0
(-7450 3925);
DISPLAY 0.872340 (-7450 3925);
PAINT GREEN (-7450 3925);
DISPLAY INVISIBLE (-7450 3925);
FORCEPROP 1 LAST OFFPAGE TRUE
J 0
(-7225 3875);
DISPLAY 0.872340 (-7225 3875);
PAINT GREEN (-7225 3875);
DISPLAY INVISIBLE (-7225 3875);
FORCEPROP 2 LAST CDS_LIB mstr_standard
J 0
(-7550 4000);
PAINT ORANGE (-7550 4000);
DISPLAY INVISIBLE (-7550 4000);
FORCEPROP 2 LAST PATH I97
J 0
(-7800 4050);
DISPLAY 1.021277 (-7800 4050);
PAINT ORANGE (-7800 4050);
DISPLAY INVISIBLE (-7800 4050);
FORCEADD OFFPAGE..1
(-6200 4300);
FORCEPROP 2 LAST $XR1 191 
J 0
(-6541 4300);
DISPLAY 0.638298 (-6541 4300);
PAINT MONO (-6541 4300);
FORCEPROP 2 LAST $XR0 55 
J 0
(-6421 4300);
DISPLAY 0.638298 (-6421 4300);
PAINT MONO (-6421 4300);
FORCEPROP 1 LAST COMMENT_BODY TRUE
J 0
(-6075 4200);
DISPLAY 0.872340 (-6075 4200);
PAINT GREEN (-6075 4200);
DISPLAY INVISIBLE (-6075 4200);
FORCEPROP 1 LAST OFFPAGE TRUE
J 0
(-5875 4175);
DISPLAY 0.872340 (-5875 4175);
PAINT GREEN (-5875 4175);
DISPLAY INVISIBLE (-5875 4175);
FORCEPROP 2 LAST ROOM BMC
J 0
(-6450 4375);
DISPLAY 1.361702 (-6450 4375);
PAINT ORANGE (-6450 4375);
DISPLAY INVISIBLE (-6450 4375);
FORCEPROP 2 LAST BOM_COST SM_CONTROLLER
J 0
(-5750 4350);
PAINT MONO (-5750 4350);
DISPLAY INVISIBLE (-5750 4350);
FORCEPROP 2 LAST CDS_LIB mstr_standard
J 0
(-6200 4300);
PAINT MONO (-6200 4300);
DISPLAY INVISIBLE (-6200 4300);
FORCEPROP 2 LAST PATH I98
J 0
(-6150 4375);
DISPLAY 1.021277 (-6150 4375);
PAINT ORANGE (-6150 4375);
DISPLAY INVISIBLE (-6150 4375);
FORCEADD OFFPAGE..1
(-6550 4200);
FORCEPROP 2 LAST $XR2 191 
J 0
(-7011 4200);
DISPLAY 0.638298 (-7011 4200);
PAINT MONO (-7011 4200);
FORCEPROP 2 LAST $XR1 151 
J 0
(-6891 4200);
DISPLAY 0.638298 (-6891 4200);
PAINT MONO (-6891 4200);
FORCEPROP 2 LAST $XR0 55 
J 0
(-6771 4200);
DISPLAY 0.638298 (-6771 4200);
PAINT MONO (-6771 4200);
FORCEPROP 2 LAST ROOM BMC
J 0
(-6800 4275);
DISPLAY 1.361702 (-6800 4275);
PAINT ORANGE (-6800 4275);
DISPLAY INVISIBLE (-6800 4275);
FORCEPROP 2 LAST BOM_COST SM_CONTROLLER
J 0
(-6100 4250);
PAINT MONO (-6100 4250);
DISPLAY INVISIBLE (-6100 4250);
FORCEPROP 2 LAST CDS_LIB mstr_standard
J 0
(-6550 4200);
PAINT MONO (-6550 4200);
DISPLAY INVISIBLE (-6550 4200);
FORCEPROP 2 LAST PATH I99
J 0
(-6500 4275);
DISPLAY 1.021277 (-6500 4275);
PAINT ORANGE (-6500 4275);
DISPLAY INVISIBLE (-6500 4275);
FORCEPROP 1 LAST OFFPAGE TRUE
J 0
(-6225 4075);
DISPLAY 0.872340 (-6225 4075);
PAINT GREEN (-6225 4075);
DISPLAY INVISIBLE (-6225 4075);
FORCEPROP 1 LAST COMMENT_BODY TRUE
J 0
(-6425 4100);
DISPLAY 0.872340 (-6425 4100);
PAINT GREEN (-6425 4100);
DISPLAY INVISIBLE (-6425 4100);
FORCEADD CAD_NOTE..1
(-7625 1875);
FORCEPROP 0 LAST L1 PLACE RESISTORS CLOSE TO BMC
J 0
(-7800 2000);
DISPLAY 0.680851 (-7800 2000);
PAINT ORANGE (-7800 2000);
FORCEPROP 1 LAST COMMENT_BODY TRUE
J 0
(-7600 1975);
DISPLAY 0.978723 (-7600 1975);
PAINT ORANGE (-7600 1975);
DISPLAY INVISIBLE (-7600 1975);
FORCEPROP 2 LAST CDS_LIB mstr_symbols
J 0
(-7625 1875);
PAINT ORANGE (-7625 1875);
DISPLAY INVISIBLE (-7625 1875);
FORCEADD INTEL_CORP_BPAGE..1
(0 0);
FORCEPROP 1 LAST CDS_CON_LAST_MODIFIED Tue Dec 01 11:52:05 2015
J 0
(-1425 325);
DISPLAY 1.361702 (-1425 325);
PAINT GREEN (-1425 325);
DISPLAY INVISIBLE (-1425 325);
FORCEPROP 1 LAST CUSTOM_TXT_CDS <CURRENT_DESIGN_SHEET> OF <TOTAL_DESIGN_SHEETS>
J 0
(-500 25);
PAINT GREEN (-500 25);
FORCEPROP 1 LAST CUSTOM_TXT_CDS <CON_LAST_MODIFIED>
J 0
(-1925 350);
PAINT GREEN (-1925 350);
FORCEPROP 2 LAST CUSTOM_TXT_CDS <XR_PAGE_TITLE>
J 0
(-7890 5250);
DISPLAY 0.638298 (-7890 5250);
PAINT PINK (-7890 5250);
DISPLAY INVISIBLE (-7890 5250);
FORCEPROP 1 LAST SCH_TITLE BMC (4 & 5 OF 7)
J 0
(-7950 50);
DISPLAY 1.212766 (-7950 50);
PAINT ORANGE (-7950 50);
FORCEPROP 1 LAST SCH_ADDRESS1 2200 Mission College Blvd.
J 0
(-3975 125);
DISPLAY 0.617021 (-3975 125);
PAINT GREEN (-3975 125);
FORCEPROP 1 LAST SCH_NUMBER H4694802
J 0
(-1300 150);
DISPLAY 1.212766 (-1300 150);
PAINT YELLOW (-1300 150);
FORCEPROP 1 LAST SCH_ADDRESS2 P.O. BOX 58119
J 0
(-3975 75);
DISPLAY 0.617021 (-3975 75);
PAINT GREEN (-3975 75);
FORCEPROP 1 LAST SCH_DEPT BESD
J 1
(-4450 100);
DISPLAY 1.212766 (-4450 100);
PAINT YELLOW (-4450 100);
FORCEPROP 1 LAST SCH_ADDRESS3 Santa Clara, CA 95052-8119
J 0
(-3975 25);
DISPLAY 0.617021 (-3975 25);
PAINT GREEN (-3975 25);
FORCEPROP 1 LAST SCH_REV 2.420
J 0
(-250 150);
DISPLAY 0.978723 (-250 150);
PAINT YELLOW (-250 150);
FORCEPROP 1 LAST COMMENT_BODY TRUE
J 0
(12 12);
DISPLAY 0.617021 (12 12);
PAINT GREEN (12 12);
DISPLAY INVISIBLE (12 12);
FORCEPROP 2 LAST PAGE_BORDER TRUE
J 0
(-7890 5250);
DISPLAY 0.851064 (-7890 5250);
PAINT PINK (-7890 5250);
DISPLAY INVISIBLE (-7890 5250);
FORCEPROP 2 LAST CDS_LIB mstr_symbols
J 0
(0 0);
DISPLAY 1.361702 (0 0);
PAINT ORANGE (0 0);
DISPLAY INVISIBLE (0 0);
FORCEPROP 2 LAST CDS_XR_PAGE_TITLE CR-146 : @BASEBOARD_FAB2_LIB.BASEBOARD_FAB2(SCH_1):PAGE146
J 0
(-7890 5250);
DISPLAY 0.638298 (-7890 5250);
PAINT PINK (-7890 5250);
DISPLAY INVISIBLE (-7890 5250);
WIRE 17 -1 (-7300 1325)(-7300 1275);
WIRE 17 -1 (-7300 1375)(-7300 1325);
WIRE 17 -1 (-7300 1425)(-7300 1375);
WIRE 17 -1 (-7600 1425)(-7300 1425);
FORCEPROP 2 LAST SIG_NAME LPC_LAD_IO<3:0>
J 0
(-7585 1435);
DISPLAY 0.680851 (-7585 1435);
PAINT ORANGE (-7585 1435);
WIRE 16 -1 (-1075 4150)(-425 4150);
WIRE 16 -1 (-425 4150)(-425 4200);
WIRE 16 -1 (-625 4200)(-425 4200);
WIRE 16 -1 (-425 4200)(-325 4200);
WIRE 16 -1 (-1750 4850)(-1750 4825);
WIRE 16 -1 (-1800 875)(-1800 1000);
WIRE 16 -1 (-5800 700)(-5800 500);
WIRE 16 -1 (-6825 2650)(-7000 2650);
WIRE 16 -1 (-6150 4550)(-5375 4550);
FORCEPROP 2 LAST SIG_NAME IRQ_PCH_NIC_ALERT_N
J 0
(-6135 4560);
DISPLAY 0.617021 (-6135 4560);
PAINT ORANGE (-6135 4560);
WIRE 16 -1 (-6150 4650)(-5375 4650);
FORCEPROP 2 LAST SIG_NAME FM_BIOS_POST_CMPLT_N
J 0
(-6125 4660);
DISPLAY 0.680851 (-6125 4660);
PAINT ORANGE (-6125 4660);
WIRE 16 -1 (-5375 3900)(-6675 3900);
FORCEPROP 2 LAST SIG_NAME FM_BMC_NMI_N_R
J 0
(-6135 3910);
DISPLAY 0.680851 (-6135 3910);
PAINT ORANGE (-6135 3910);
FORCEPROP 2 LASTPROP $XRERR UNIQUE?
J 0
(-6375 3910);
DISPLAY 0.638298 (-6375 3910);
PAINT MONO (-6375 3910);
DISPLAY INVISIBLE (-6375 3910);
WIRE 16 -1 (-6850 3900)(-6675 3900);
WIRE 16 -1 (-6675 3825)(-6675 3900);
WIRE 16 -1 (-6850 3825)(-6675 3825);
WIRE 16 -1 (-6525 3950)(-5375 3950);
FORCEPROP 2 LAST SIG_NAME FM_BMC_SYS_THROTTLE_R_N
J 0
(-6135 3960);
DISPLAY 0.680851 (-6135 3960);
PAINT ORANGE (-6135 3960);
FORCEPROP 2 LASTPROP $XRERR UNIQUE?
J 0
(-6375 3960);
DISPLAY 0.638298 (-6375 3960);
PAINT MONO (-6375 3960);
DISPLAY INVISIBLE (-6375 3960);
WIRE 16 -1 (-6150 4300)(-5375 4300);
FORCEPROP 2 LAST SIG_NAME FM_CPU1_PROC_ID1
J 0
(-6125 4310);
DISPLAY 0.680851 (-6125 4310);
PAINT ORANGE (-6125 4310);
WIRE 16 -1 (-6150 4350)(-5375 4350);
FORCEPROP 2 LAST SIG_NAME IRQ_SML1_PMBUS_ALERT_N
J 2
(-5575 4360);
DISPLAY 0.680851 (-5575 4360);
PAINT ORANGE (-5575 4360);
WIRE 16 -1 (-6500 4400)(-5375 4400);
FORCEPROP 0 LAST SIG_NAME IRQ_OOB_MGMT_RISER_ALERT_N
J 2
(-5650 4410);
DISPLAY 0.680851 (-5650 4410);
PAINT ORANGE (-5650 4410);
WIRE 16 -1 (-6525 4150)(-5375 4150);
FORCEPROP 2 LAST SIG_NAME H_CPU0_MEMABC_MEMHOT_LVT3_BMC_N
J 0
(-6525 4160);
DISPLAY 0.680851 (-6525 4160);
PAINT ORANGE (-6525 4160);
WIRE 16 -1 (-6175 4000)(-5375 4000);
FORCEPROP 2 LAST SIG_NAME IRQ_BMC_PCH_SCI_LPC_N
J 2
(-5600 4010);
DISPLAY 0.680851 (-5600 4010);
PAINT ORANGE (-5600 4010);
WIRE 16 -1 (-6625 2650)(-5575 2650);
FORCEPROP 2 LAST SIG_NAME PD_SP_ENTEST
J 0
(-6135 2660);
DISPLAY 0.680851 (-6135 2660);
PAINT ORANGE (-6135 2660);
FORCEPROP 2 LASTPROP $XRERR UNIQUE?
J 0
(-6375 2660);
DISPLAY 0.638298 (-6375 2660);
PAINT MONO (-6375 2660);
DISPLAY INVISIBLE (-6375 2660);
WIRE 16 -1 (-2625 2050)(-1700 2050);
FORCEPROP 2 LAST SIG_NAME SPI_BMC_BT_CS1_N
J 0
(-2485 2060);
DISPLAY 0.680851 (-2485 2060);
PAINT ORANGE (-2485 2060);
WIRE 16 -1 (-2625 1950)(-1700 1950);
FORCEPROP 2 LAST SIG_NAME SPI_BMC_CS0_N
J 2
(-2150 1960);
DISPLAY 0.680851 (-2150 1960);
PAINT ORANGE (-2150 1960);
WIRE 16 -1 (-2625 1900)(-1700 1900);
FORCEPROP 2 LAST SIG_NAME SPI_BMC_CLK
J 2
(-2200 1910);
DISPLAY 0.680851 (-2200 1910);
PAINT ORANGE (-2200 1910);
WIRE 16 -1 (-2625 1850)(-1700 1850);
FORCEPROP 2 LAST SIG_NAME SPI_BMC_DO
J 2
(-2225 1860);
DISPLAY 0.680851 (-2225 1860);
PAINT ORANGE (-2225 1860);
WIRE 16 -1 (-2625 1800)(-1700 1800);
FORCEPROP 2 LAST SIG_NAME SPI_BMC_DI
J 2
(-2250 1810);
DISPLAY 0.680851 (-2250 1810);
PAINT ORANGE (-2250 1810);
WIRE 16 -1 (-2625 1650)(-1800 1650);
FORCEPROP 2 LAST SIG_NAME FM_PE_BMC_WAKE_N
J 0
(-2435 1660);
DISPLAY 0.680851 (-2435 1660);
PAINT ORANGE (-2435 1660);
WIRE 16 -1 (-1800 1650)(-1700 1650);
WIRE 16 -1 (-1800 1200)(-1800 1650);
WIRE 16 -1 (-2550 1525)(-1375 1525);
FORCEPROP 2 LAST SIG_NAME FM_CPU0_FIVR_FAULT_LVT3_R_N
J 0
(-2535 1535);
DISPLAY 0.680851 (-2535 1535);
PAINT ORANGE (-2535 1535);
FORCEPROP 2 LASTPROP $XRERR UNIQUE?
J 0
(-2775 1535);
DISPLAY 0.638298 (-2775 1535);
PAINT MONO (-2775 1535);
DISPLAY INVISIBLE (-2775 1535);
WIRE 16 -1 (-2550 1525)(-2550 1600);
WIRE 16 -1 (-2625 1600)(-2550 1600);
WIRE 16 -1 (-2625 2000)(-1700 2000);
FORCEPROP 0 LAST SIG_NAME FM_CPU1_THERMTRIP_LATCH_LVT3_N
J 0
(-2500 2010);
DISPLAY 0.680851 (-2500 2010);
PAINT ORANGE (-2500 2010);
WIRE 16 -1 (-1175 1525)(-350 1525);
FORCEPROP 2 LAST SIG_NAME FM_CPU0_FIVR_FAULT_LVT3_N
J 0
(-960 1535);
DISPLAY 0.617021 (-960 1535);
PAINT ORANGE (-960 1535);
WIRE 16 -1 (-1900 2600)(-2625 2600);
FORCEPROP 2 LAST SIG_NAME BMC_M_MALERT_N
J 0
(-2435 2610);
DISPLAY 0.680851 (-2435 2610);
PAINT ORANGE (-2435 2610);
WIRE 16 -1 (-1900 2650)(-2625 2650);
FORCEPROP 2 LAST SIG_NAME BMC_M_RST_N
J 0
(-2435 2660);
DISPLAY 0.680851 (-2435 2660);
PAINT ORANGE (-2435 2660);
WIRE 16 -1 (-6325 1500)(-5800 1500);
FORCEPROP 0 LAST SIG_NAME CLK_24M_BMC_LPC_R1
J 0
(-6203 1502);
DISPLAY 0.680851 (-6203 1502);
PAINT ORANGE (-6203 1502);
FORCEPROP 2 LASTPROP $XRERR UNIQUE?
J 0
(-6443 1502);
DISPLAY 0.638298 (-6443 1502);
PAINT MONO (-6443 1502);
DISPLAY INVISIBLE (-6443 1502);
WIRE 16 -1 (-5800 1500)(-5575 1500);
WIRE 16 -1 (-5800 900)(-5800 1500);
WIRE 16 -1 (-6325 1600)(-5750 1600);
FORCEPROP 0 LAST SIG_NAME LPC_LFRAME_N_CS0_R_N
J 0
(-6250 1610);
DISPLAY 0.680851 (-6250 1610);
PAINT ORANGE (-6250 1610);
FORCEPROP 2 LASTPROP $XRERR UNIQUE?
J 0
(-6490 1610);
DISPLAY 0.638298 (-6490 1610);
PAINT MONO (-6490 1610);
DISPLAY INVISIBLE (-6490 1610);
WIRE 16 -1 (-5750 1600)(-5750 1550);
WIRE 16 -1 (-5750 1550)(-5575 1550);
WIRE 16 -1 (-6325 1675)(-5700 1675);
FORCEPROP 0 LAST SIG_NAME IRQ_LPC_SERIRQ_R
J 0
(-6175 1685);
DISPLAY 0.680851 (-6175 1685);
PAINT ORANGE (-6175 1685);
FORCEPROP 2 LASTPROP $XRERR UNIQUE?
J 0
(-6415 1685);
DISPLAY 0.638298 (-6415 1685);
PAINT MONO (-6415 1685);
DISPLAY INVISIBLE (-6415 1685);
WIRE 16 -1 (-5700 1675)(-5700 1600);
WIRE 16 -1 (-5700 1600)(-5575 1600);
WIRE 16 -1 (-5650 1750)(-5650 1650);
WIRE 16 -1 (-5650 1750)(-6325 1750);
FORCEPROP 0 LAST SIG_NAME RST_BMC_LVC3_N
J 0
(-5975 1760);
DISPLAY 0.680851 (-5975 1760);
PAINT ORANGE (-5975 1760);
FORCEPROP 2 LASTPROP $XRERR UNIQUE?
J 0
(-6215 1760);
DISPLAY 0.638298 (-6215 1760);
PAINT MONO (-6215 1760);
DISPLAY INVISIBLE (-6215 1760);
WIRE 16 -1 (-5650 1650)(-5575 1650);
WIRE 16 682 (-6275 1475)(-6275 1925);
WIRE 16 682 (-7800 1475)(-6275 1475);
WIRE 16 682 (-6275 1925)(-7800 1925);
WIRE 16 -1 (-5575 2500)(-6200 2500);
FORCEPROP 2 LAST SIG_NAME SPI_BMC_BT_DO_R
J 0
(-6035 2510);
DISPLAY 0.680851 (-6035 2510);
PAINT ORANGE (-6035 2510);
FORCEPROP 2 LASTPROP $XRERR UNIQUE?
J 0
(-6275 2510);
DISPLAY 0.638298 (-6275 2510);
PAINT MONO (-6275 2510);
DISPLAY INVISIBLE (-6275 2510);
WIRE 16 -1 (-6325 3400)(-5375 3400);
FORCEPROP 2 LAST SIG_NAME FM_THROTTLE_N
J 0
(-6285 3410);
DISPLAY 0.680851 (-6285 3410);
PAINT ORANGE (-6285 3410);
WIRE 16 -1 (-6375 3450)(-5375 3450);
FORCEPROP 0 LAST SIG_NAME FM_BMC_READY_N
J 0
(-6350 3460);
DISPLAY 0.680851 (-6350 3460);
PAINT ORANGE (-6350 3460);
WIRE 16 -1 (-6350 3500)(-5375 3500);
FORCEPROP 0 LAST $PHYS_NET_NAME IRQ_MEZZ_LAN_ALERT_N
J 0
(-5375 3586);
PAINT MONO (-5375 3586);
DISPLAY INVISIBLE (-5375 3586);
FORCEPROP 0 LAST CDS_PHYS_NET_NAME IRQ_MEZZ_LAN_ALERT_N
J 0
(-5375 3539);
PAINT MONO (-5375 3539);
DISPLAY INVISIBLE (-5375 3539);
FORCEPROP 2 LAST SIG_NAME IRQ_MEZZ_LAN_ALERT_N
J 2
(-5650 3510);
DISPLAY 0.680851 (-5650 3510);
PAINT ORANGE (-5650 3510);
WIRE 16 -1 (-6350 3550)(-5375 3550);
FORCEPROP 2 LAST SIG_NAME IRQ_LOM_ALERT_N
J 2
(-5750 3560);
DISPLAY 0.680851 (-5750 3560);
PAINT ORANGE (-5750 3560);
WIRE 16 -1 (-6350 3600)(-5375 3600);
FORCEPROP 0 LAST SIG_NAME H_CPU0_MEMDEF_MEMHOT_LVT3_BMC_N
J 0
(-6375 3610);
DISPLAY 0.680851 (-6375 3610);
PAINT ORANGE (-6375 3610);
WIRE 16 -1 (-7500 4000)(-6725 4000);
FORCEPROP 0 LAST CDS_PHYS_NET_NAME IRQ_FORCE_NM_THROTTLE_N
J 0
(-7500 4039);
PAINT MONO (-7500 4039);
DISPLAY INVISIBLE (-7500 4039);
FORCEPROP 2 LAST SIG_NAME IRQ_FORCE_NM_THROTTLE_N
J 0
(-7500 4010);
DISPLAY 0.617021 (-7500 4010);
PAINT ORANGE (-7500 4010);
WIRE 16 -1 (-6725 4000)(-6725 3950);
WIRE 16 -1 (-5600 1250)(-5600 1300);
WIRE 16 -1 (-5600 1250)(-6400 1250);
FORCEPROP 2 LAST SIG_NAME LPC_LAD0_IO0_R
J 0
(-6210 1260);
DISPLAY 0.680851 (-6210 1260);
PAINT ORANGE (-6210 1260);
FORCEPROP 2 LASTPROP $XRERR UNIQUE?
J 0
(-6450 1260);
DISPLAY 0.638298 (-6450 1260);
PAINT MONO (-6450 1260);
DISPLAY INVISIBLE (-6450 1260);
WIRE 16 -1 (-5600 1300)(-5575 1300);
WIRE 16 -1 (-5675 1350)(-5675 1400);
WIRE 16 -1 (-5675 1350)(-6400 1350);
FORCEPROP 2 LAST SIG_NAME LPC_LAD2_IO2_R
J 0
(-6210 1360);
DISPLAY 0.680851 (-6210 1360);
PAINT ORANGE (-6210 1360);
FORCEPROP 2 LASTPROP $XRERR UNIQUE?
J 0
(-6450 1360);
DISPLAY 0.638298 (-6450 1360);
PAINT MONO (-6450 1360);
DISPLAY INVISIBLE (-6450 1360);
WIRE 16 -1 (-5675 1400)(-5575 1400);
WIRE 16 -1 (-6600 2200)(-5575 2200);
FORCEPROP 2 LAST SIG_NAME TP_DDCCLK_GPIOJ6
J 0
(-6510 2210);
DISPLAY 0.680851 (-6510 2210);
PAINT ORANGE (-6510 2210);
FORCEPROP 2 LASTPROP $XRERR UNIQUE?
J 0
(-6840 2200);
DISPLAY 0.638298 (-6840 2200);
PAINT MONO (-6840 2200);
DISPLAY INVISIBLE (-6840 2200);
WIRE 16 -1 (-6600 2250)(-5575 2250);
FORCEPROP 2 LAST SIG_NAME TP_DDCDAT_GPIOJ7
J 0
(-6510 2260);
DISPLAY 0.680851 (-6510 2260);
PAINT ORANGE (-6510 2260);
FORCEPROP 2 LASTPROP $XRERR UNIQUE?
J 0
(-6840 2250);
DISPLAY 0.638298 (-6840 2250);
PAINT MONO (-6840 2250);
DISPLAY INVISIBLE (-6840 2250);
WIRE 16 -1 (-5575 2350)(-6125 2350);
FORCEPROP 2 LAST SIG_NAME SPI_BMC_BT_CLK_R
J 0
(-6135 2360);
DISPLAY 0.680851 (-6135 2360);
PAINT ORANGE (-6135 2360);
FORCEPROP 2 LASTPROP $XRERR UNIQUE?
J 0
(-6375 2360);
DISPLAY 0.638298 (-6375 2360);
PAINT MONO (-6375 2360);
DISPLAY INVISIBLE (-6375 2360);
WIRE 16 -1 (-6450 2400)(-5575 2400);
FORCEPROP 2 LAST SIG_NAME SPI_BMC_BT_CS_R_N
J 0
(-6185 2410);
DISPLAY 0.680851 (-6185 2410);
PAINT ORANGE (-6185 2410);
FORCEPROP 2 LASTPROP $XRERR UNIQUE?
J 0
(-6425 2410);
DISPLAY 0.638298 (-6425 2410);
PAINT MONO (-6425 2410);
DISPLAY INVISIBLE (-6425 2410);
WIRE 16 -1 (-6600 2050)(-5575 2050);
FORCEPROP 2 LAST SIG_NAME TP_VGAVS_GPIOJ5
J 0
(-6510 2060);
DISPLAY 0.680851 (-6510 2060);
PAINT ORANGE (-6510 2060);
FORCEPROP 2 LASTPROP $XRERR UNIQUE?
J 0
(-6840 2050);
DISPLAY 0.638298 (-6840 2050);
PAINT MONO (-6840 2050);
DISPLAY INVISIBLE (-6840 2050);
WIRE 16 -1 (-6600 2000)(-5575 2000);
FORCEPROP 2 LAST SIG_NAME TP_VGAHS_GPIOJ4
J 0
(-6510 2010);
DISPLAY 0.680851 (-6510 2010);
PAINT ORANGE (-6510 2010);
FORCEPROP 2 LASTPROP $XRERR UNIQUE?
J 0
(-6840 2000);
DISPLAY 0.638298 (-6840 2000);
PAINT MONO (-6840 2000);
DISPLAY INVISIBLE (-6840 2000);
WIRE 16 -1 (-2375 3850)(-1650 3850);
FORCEPROP 2 LAST SIG_NAME LED_POSTCODE_3
J 2
(-1725 3860);
DISPLAY 0.680851 (-1725 3860);
PAINT ORANGE (-1725 3860);
WIRE 16 -1 (-2375 3900)(-1650 3900);
FORCEPROP 2 LAST SIG_NAME LED_POSTCODE_4
J 2
(-1725 3910);
DISPLAY 0.680851 (-1725 3910);
PAINT ORANGE (-1725 3910);
WIRE 16 -1 (-2375 3950)(-1650 3950);
FORCEPROP 2 LAST SIG_NAME LED_POSTCODE_5
J 2
(-1725 3960);
DISPLAY 0.680851 (-1725 3960);
PAINT ORANGE (-1725 3960);
WIRE 16 -1 (-7475 3900)(-7050 3900);
FORCEPROP 2 LAST SIG_NAME FM_BMC_NMI_N
J 0
(-7460 3910);
DISPLAY 0.617021 (-7460 3910);
PAINT ORANGE (-7460 3910);
WIRE 16 -1 (-7475 3825)(-7050 3825);
FORCEPROP 2 LAST SIG_NAME IRQ_SML0_ALERT_N
J 2
(-7125 3835);
DISPLAY 0.617021 (-7125 3835);
PAINT ORANGE (-7125 3835);
WIRE 16 -1 (-6350 3750)(-5375 3750);
FORCEPROP 2 LAST SIG_NAME GPIOS7
J 0
(-6325 3760);
DISPLAY 0.680851 (-6325 3760);
PAINT ORANGE (-6325 3760);
WIRE 16 -1 (-6350 3700)(-5375 3700);
FORCEPROP 0 LAST SIG_NAME FP_PWR_ID_LED_N
J 0
(-6325 3710);
DISPLAY 0.680851 (-6325 3710);
PAINT ORANGE (-6325 3710);
WIRE 16 -1 (-6350 3650)(-5375 3650);
FORCEPROP 2 LAST SIG_NAME FM_SPEAKER_PCH_N
J 0
(-6335 3660);
DISPLAY 0.680851 (-6335 3660);
PAINT ORANGE (-6335 3660);
WIRE 16 -1 (-6500 4200)(-5375 4200);
FORCEPROP 2 LAST SIG_NAME FM_CPU1_PROC_ID0
J 0
(-6500 4210);
DISPLAY 0.680851 (-6500 4210);
PAINT ORANGE (-6500 4210);
WIRE 16 -1 (-6300 4100)(-5375 4100);
FORCEPROP 0 LAST SIG_NAME FM_CPU0_THERMTRIP_LATCH_LVT3_N
J 0
(-6275 4110);
DISPLAY 0.680851 (-6275 4110);
PAINT ORANGE (-6275 4110);
WIRE 16 -1 (-7125 2500)(-6400 2500);
FORCEPROP 2 LAST SIG_NAME SPI_BMC_BT_DO
J 0
(-7050 2510);
DISPLAY 0.680851 (-7050 2510);
PAINT ORANGE (-7050 2510);
WIRE 16 -1 (-7100 2450)(-5575 2450);
FORCEPROP 2 LAST SIG_NAME SPI_BMC_BT_DI
J 0
(-6025 2460);
DISPLAY 0.680851 (-6025 2460);
PAINT ORANGE (-6025 2460);
WIRE 16 -1 (-7125 2350)(-6325 2350);
FORCEPROP 2 LAST SIG_NAME SPI_BMC_BT_CLK
J 0
(-7125 2360);
DISPLAY 0.680851 (-7125 2360);
PAINT ORANGE (-7125 2360);
WIRE 16 -1 (-2375 3750)(-1650 3750);
FORCEPROP 2 LAST SIG_NAME LED_POSTCODE_1
J 2
(-1725 3760);
DISPLAY 0.680851 (-1725 3760);
PAINT ORANGE (-1725 3760);
WIRE 16 -1 (-2375 3700)(-1650 3700);
FORCEPROP 2 LAST SIG_NAME LED_POSTCODE_0
J 2
(-1725 3710);
DISPLAY 0.680851 (-1725 3710);
PAINT ORANGE (-1725 3710);
WIRE 16 -1 (-2375 4300)(-1675 4300);
FORCEPROP 2 LAST SIG_NAME USB2_PCH_BMC_P5_DN
J 0
(-2225 4310);
DISPLAY 0.680851 (-2225 4310);
PAINT ORANGE (-2225 4310);
WIRE 16 -1 (-6175 4050)(-5375 4050);
FORCEPROP 2 LAST SIG_NAME HSC_SMBUS_SWITCH_EN
J 0
(-6135 4060);
DISPLAY 0.680851 (-6135 4060);
PAINT ORANGE (-6135 4060);
WIRE 16 -1 (-6175 3850)(-5375 3850);
FORCEPROP 2 LAST SIG_NAME FM_BIOS_SPI_BMC_CTRL
J 0
(-6135 3860);
DISPLAY 0.680851 (-6135 3860);
PAINT ORANGE (-6135 3860);
WIRE 16 -1 (-6950 1400)(-7200 1400);
WIRE 16 -1 (-6600 1350)(-7200 1350);
WIRE 16 -1 (-6950 1300)(-7200 1300);
WIRE 16 -1 (-6600 1250)(-7200 1250);
WIRE 16 -1 (-7100 1500)(-6525 1500);
FORCEPROP 0 LAST SIG_NAME CLK_24M_BMC_LPC
J 0
(-7086 1510);
DISPLAY 0.617021 (-7086 1510);
PAINT ORANGE (-7086 1510);
WIRE 16 -1 (-7075 1675)(-6525 1675);
FORCEPROP 0 LAST SIG_NAME IRQ_LPC_SERIRQ_N
J 0
(-7075 1685);
DISPLAY 0.680851 (-7075 1685);
PAINT ORANGE (-7075 1685);
WIRE 16 -1 (-7125 2400)(-6650 2400);
FORCEPROP 2 LAST SIG_NAME SPI_BMC_BT_CS_N
J 0
(-7135 2410);
DISPLAY 0.680851 (-7135 2410);
PAINT ORANGE (-7135 2410);
WIRE 16 -1 (-7075 1600)(-6525 1600);
FORCEPROP 0 LAST SIG_NAME LPC_LFRAME_N_CS0_N
J 0
(-7075 1610);
DISPLAY 0.680851 (-7075 1610);
PAINT ORANGE (-7075 1610);
WIRE 16 -1 (-7075 1750)(-6525 1750);
FORCEPROP 0 LAST SIG_NAME RST_PLTRST_BUF_N
J 0
(-7075 1760);
DISPLAY 0.680851 (-7075 1760);
PAINT ORANGE (-7075 1760);
WIRE 16 -1 (-1675 4500)(-1750 4500);
WIRE 16 -1 (-1750 4500)(-1750 4625);
WIRE 16 -1 (-2375 4500)(-1750 4500);
FORCEPROP 2 LAST SIG_NAME USB_PCH_BMC_P4_DP
J 0
(-2225 4510);
DISPLAY 0.680851 (-2225 4510);
PAINT ORANGE (-2225 4510);
WIRE 16 -1 (-825 4200)(-2375 4200);
FORCEPROP 2 LAST SIG_NAME A_USB2AVRES
J 0
(-2210 4210);
DISPLAY 0.680851 (-2210 4210);
PAINT ORANGE (-2210 4210);
FORCEPROP 2 LASTPROP $XRERR UNIQUE?
J 0
(-2450 4210);
DISPLAY 0.638298 (-2450 4210);
PAINT MONO (-2450 4210);
DISPLAY INVISIBLE (-2450 4210);
WIRE 16 -1 (-2375 4450)(-1675 4450);
FORCEPROP 2 LAST SIG_NAME USB_PCH_BMC_P4_DN
J 0
(-2225 4460);
DISPLAY 0.680851 (-2225 4460);
PAINT ORANGE (-2225 4460);
WIRE 16 -1 (-2375 4350)(-1675 4350);
FORCEPROP 2 LAST SIG_NAME USB2_PCH_BMC_P5_DP
J 0
(-2225 4360);
DISPLAY 0.680851 (-2225 4360);
PAINT ORANGE (-2225 4360);
WIRE 16 -1 (-2375 4150)(-1275 4150);
FORCEPROP 2 LAST SIG_NAME A_USB2BVRES
J 0
(-2210 4160);
DISPLAY 0.680851 (-2210 4160);
PAINT ORANGE (-2210 4160);
FORCEPROP 2 LASTPROP $XRERR UNIQUE?
J 0
(-2450 4160);
DISPLAY 0.638298 (-2450 4160);
PAINT MONO (-2450 4160);
DISPLAY INVISIBLE (-2450 4160);
WIRE 16 -1 (-2375 4050)(-1650 4050);
FORCEPROP 2 LAST SIG_NAME LED_POSTCODE_7
J 2
(-1725 4060);
DISPLAY 0.680851 (-1725 4060);
PAINT ORANGE (-1725 4060);
WIRE 16 -1 (-2375 4000)(-1650 4000);
FORCEPROP 2 LAST SIG_NAME LED_POSTCODE_6
J 2
(-1725 4010);
DISPLAY 0.680851 (-1725 4010);
PAINT ORANGE (-1725 4010);
WIRE 16 -1 (-5650 1350)(-5575 1350);
WIRE 16 -1 (-5650 1300)(-5650 1350);
WIRE 16 -1 (-5650 1300)(-6750 1300);
FORCEPROP 2 LAST SIG_NAME LPC_LAD1_IO1_R
J 0
(-6210 1310);
DISPLAY 0.680851 (-6210 1310);
PAINT ORANGE (-6210 1310);
FORCEPROP 2 LASTPROP $XRERR UNIQUE?
J 0
(-6450 1310);
DISPLAY 0.638298 (-6450 1310);
PAINT MONO (-6450 1310);
DISPLAY INVISIBLE (-6450 1310);
WIRE 16 -1 (-5700 1450)(-5575 1450);
WIRE 16 -1 (-5700 1400)(-5700 1450);
WIRE 16 -1 (-6750 1400)(-5700 1400);
FORCEPROP 2 LAST SIG_NAME LPC_LAD3_IO3_R
J 0
(-6210 1410);
DISPLAY 0.680851 (-6210 1410);
PAINT ORANGE (-6210 1410);
FORCEPROP 2 LASTPROP $XRERR UNIQUE?
J 0
(-6450 1410);
DISPLAY 0.638298 (-6450 1410);
PAINT MONO (-6450 1410);
DISPLAY INVISIBLE (-6450 1410);
WIRE 16 -1 (-2375 3800)(-1650 3800);
FORCEPROP 2 LAST SIG_NAME LED_POSTCODE_2
J 2
(-1725 3810);
DISPLAY 0.680851 (-1725 3810);
PAINT ORANGE (-1725 3810);
DOT 1 (-1800 1650);
DOT 1 (-1750 4500);
DOT 1 (-425 4200);
DOT 1 (-6675 3900);
DOT 1 (-5800 1500);
FORCENOTE
CHECK
(-6075 750) 0;
DISPLAY LEFT (-6075 750);
DISPLAY 1.021277 (-6075 750);
PAINT RED (-6075 750);
QUIT
